FILE_TYPE = MACRO_DRAWING;
SET COLOR_WIRE YELLOW;
SET COLOR_PROP MONO;
SET COLOR_DOT WHITE;
SET COLOR_ARC YELLOW;
SET COLOR_BODY GREEN;
SET COLOR_NOTE MONO;
SET PROP_DISPLAY VALUE;
SET PAGE_NUMBER P174;
FORCEADD OFFPAGE..1
(11100 4575);
FORCEPROP 2 LAST $XR0 116 
J 0
(10848 4575);
DISPLAY 0.638298 (10848 4575);
PAINT MONO (10848 4575);
FORCEPROP 2 LAST CDS_LIB mstr_standard
J 0
(11100 4575);
PAINT ORANGE (11100 4575);
DISPLAY INVISIBLE (11100 4575);
FORCEPROP 1 LAST OFFPAGE TRUE
J 0
(11425 4450);
DISPLAY 0.872340 (11425 4450);
PAINT GREEN (11425 4450);
DISPLAY INVISIBLE (11425 4450);
FORCEPROP 1 LAST COMMENT_BODY TRUE
J 0
(11225 4475);
DISPLAY 0.872340 (11225 4475);
PAINT GREEN (11225 4475);
DISPLAY INVISIBLE (11225 4475);
FORCEPROP 2 LAST PATH I1
J 0
(10825 4625);
DISPLAY 1.021277 (10825 4625);
PAINT ORANGE (10825 4625);
DISPLAY INVISIBLE (10825 4625);
FORCEADD TAP..1
(11800 3025);
FORCEPROP 3 LASTPIN (11750 3025) SIG_NAME SATA6G_TX_DN<1>
J 0
(11760 3035);
DISPLAY 0.659574 (11760 3035);
PAINT MONO (11760 3035);
DISPLAY INVISIBLE (11760 3035);
FORCEPROP 1 LASTPIN (11750 3025) BN 1
J 0
(11738 3033);
DISPLAY 0.617021 (11738 3033);
PAINT GREEN (11738 3033);
FORCEPROP 2 LAST CDS_LIB mstr_standard
J 0
(11800 3025);
PAINT ORANGE (11800 3025);
DISPLAY INVISIBLE (11800 3025);
FORCEPROP 1 LAST BODY_TYPE PLUMBING
J 0
(11800 3075);
DISPLAY 0.872340 (11800 3075);
PAINT GREEN (11800 3075);
DISPLAY INVISIBLE (11800 3075);
FORCEPROP 1 LAST HDL_TAP TRUE
J 0
(12125 2900);
DISPLAY 0.872340 (12125 2900);
PAINT ORANGE (12125 2900);
DISPLAY INVISIBLE (12125 2900);
FORCEPROP 1 LAST PATH I10
J 0
(11798 3025);
DISPLAY 0.872340 (11798 3025);
PAINT GREEN (11798 3025);
DISPLAY INVISIBLE (11798 3025);
FORCEADD TAP..1
(11800 2250);
FORCEPROP 3 LASTPIN (11750 2250) SIG_NAME SATA6G_TX_DN<2>
J 0
(11760 2260);
DISPLAY 0.659574 (11760 2260);
PAINT MONO (11760 2260);
DISPLAY INVISIBLE (11760 2260);
FORCEPROP 1 LASTPIN (11750 2250) BN 2
J 0
(11738 2258);
DISPLAY 0.617021 (11738 2258);
PAINT GREEN (11738 2258);
FORCEPROP 2 LAST CDS_LIB mstr_standard
J 0
(11800 2250);
PAINT ORANGE (11800 2250);
DISPLAY INVISIBLE (11800 2250);
FORCEPROP 1 LAST BODY_TYPE PLUMBING
J 0
(11800 2300);
DISPLAY 0.872340 (11800 2300);
PAINT GREEN (11800 2300);
DISPLAY INVISIBLE (11800 2300);
FORCEPROP 1 LAST HDL_TAP TRUE
J 0
(12125 2125);
DISPLAY 0.872340 (12125 2125);
PAINT ORANGE (12125 2125);
DISPLAY INVISIBLE (12125 2125);
FORCEPROP 1 LAST PATH I11
J 0
(11798 2250);
DISPLAY 0.872340 (11798 2250);
PAINT GREEN (11798 2250);
DISPLAY INVISIBLE (11798 2250);
FORCEADD CAP_A..2
(11225 3025);
FORCEPROP 1 LAST LOCATION C1L7
J 1
(11225 3125);
DISPLAY 0.617021 (11225 3125);
PAINT AQUA (11225 3125);
FORCEPROP 1 LAST PART_NUMBER A36096-045
J 1
(11225 3075);
DISPLAY 0.617021 (11225 3075);
PAINT BLUE (11225 3075);
FORCEPROP 1 LAST VALUE 0.01UF
J 2
(11225 2925);
DISPLAY 0.617021 (11225 2925);
PAINT SKYBLUE (11225 2925);
FORCEPROP 1 LAST TOLERANCE 10%
J 2
(11225 2875);
DISPLAY 0.617021 (11225 2875);
PAINT SKYBLUE (11225 2875);
FORCEPROP 1 LAST PACK_TYPE 0402V
J 1
(11225 2825);
DISPLAY 0.617021 (11225 2825);
PAINT SKYBLUE (11225 2825);
FORCEPROP 1 LAST VOLTAGE 25V
J 0
(11225 2925);
DISPLAY 0.617021 (11225 2925);
PAINT SKYBLUE (11225 2925);
FORCEPROP 1 LAST MATERIAL X7R
J 0
(11225 2875);
DISPLAY 0.617021 (11225 2875);
PAINT SKYBLUE (11225 2875);
FORCEPROP 2 LAST CDS_LOCATION C1L7
J 1
(11225 3125);
DISPLAY 0.617021 (11225 3125);
PAINT AQUA (11225 3125);
DISPLAY INVISIBLE (11225 3125);
FORCEPROP 2 LAST BOM_COST ST_SATA
J 0
(11175 3175);
DISPLAY 1.361702 (11175 3175);
PAINT ORANGE (11175 3175);
DISPLAY INVISIBLE (11175 3175);
FORCEPROP 2 LAST CDS_LIB dev_discrete
J 0
(11225 3025);
PAINT ORANGE (11225 3025);
DISPLAY INVISIBLE (11225 3025);
FORCEPROP 2 LAST CDS_SEC 1
J 0
(11225 3275);
DISPLAY 1.021277 (11225 3275);
PAINT ORANGE (11225 3275);
DISPLAY INVISIBLE (11225 3275);
FORCEPROP 2 LAST $SEC 1
J 0
(11225 3275);
DISPLAY 0.680851 (11225 3275);
PAINT MONO (11225 3275);
DISPLAY INVISIBLE (11225 3275);
FORCEPROP 1 LAST PATH I12
J 0
(11225 3225);
DISPLAY 0.978723 (11225 3225);
PAINT WHITE (11225 3225);
DISPLAY INVISIBLE (11225 3225);
FORCEPROP 2 LAST ROOM ST_SATA
J 0
(11175 3175);
DISPLAY 1.361702 (11175 3175);
PAINT ORANGE (11175 3175);
DISPLAY INVISIBLE (11175 3175);
FORCEPROP 1 LASTPIN (11125 3025) $PN 1
J 0
(11115 3040);
DISPLAY 0.787234 (11115 3040);
PAINT ORANGE (11115 3040);
DISPLAY INVISIBLE (11115 3040);
FORCEPROP 1 LASTPIN (11325 3025) $PN 2
J 0
(11310 3040);
DISPLAY 0.787234 (11310 3040);
PAINT ORANGE (11310 3040);
DISPLAY INVISIBLE (11310 3040);
FORCEADD CAP_A..2
(10925 3250);
FORCEPROP 1 LAST LOCATION C1L6
J 1
(10925 3350);
DISPLAY 0.617021 (10925 3350);
PAINT AQUA (10925 3350);
FORCEPROP 1 LAST PART_NUMBER A36096-045
J 1
(10925 3300);
DISPLAY 0.617021 (10925 3300);
PAINT BLUE (10925 3300);
FORCEPROP 1 LAST VALUE 0.01UF
J 2
(10925 3150);
DISPLAY 0.617021 (10925 3150);
PAINT SKYBLUE (10925 3150);
FORCEPROP 1 LAST TOLERANCE 10%
J 2
(10925 3100);
DISPLAY 0.617021 (10925 3100);
PAINT SKYBLUE (10925 3100);
FORCEPROP 1 LAST PACK_TYPE 0402V
J 1
(10925 3050);
DISPLAY 0.617021 (10925 3050);
PAINT SKYBLUE (10925 3050);
FORCEPROP 1 LAST VOLTAGE 25V
J 0
(10925 3150);
DISPLAY 0.617021 (10925 3150);
PAINT SKYBLUE (10925 3150);
FORCEPROP 1 LAST MATERIAL X7R
J 0
(10925 3100);
DISPLAY 0.617021 (10925 3100);
PAINT SKYBLUE (10925 3100);
FORCEPROP 2 LAST CDS_LOCATION C1L6
J 1
(10925 3350);
DISPLAY 0.617021 (10925 3350);
PAINT AQUA (10925 3350);
DISPLAY INVISIBLE (10925 3350);
FORCEPROP 2 LAST BOM_COST ST_SATA
J 0
(10825 3400);
DISPLAY 1.361702 (10825 3400);
PAINT ORANGE (10825 3400);
DISPLAY INVISIBLE (10825 3400);
FORCEPROP 2 LAST CDS_LIB dev_discrete
J 0
(10925 3250);
PAINT ORANGE (10925 3250);
DISPLAY INVISIBLE (10925 3250);
FORCEPROP 2 LAST CDS_SEC 1
J 0
(10925 3500);
DISPLAY 1.021277 (10925 3500);
PAINT ORANGE (10925 3500);
DISPLAY INVISIBLE (10925 3500);
FORCEPROP 2 LAST $SEC 1
J 0
(10925 3500);
DISPLAY 0.680851 (10925 3500);
PAINT MONO (10925 3500);
DISPLAY INVISIBLE (10925 3500);
FORCEPROP 1 LAST PATH I13
J 0
(10925 3450);
DISPLAY 0.978723 (10925 3450);
PAINT WHITE (10925 3450);
DISPLAY INVISIBLE (10925 3450);
FORCEPROP 2 LAST ROOM ST_SATA
J 0
(10825 3400);
DISPLAY 1.361702 (10825 3400);
PAINT ORANGE (10825 3400);
DISPLAY INVISIBLE (10825 3400);
FORCEPROP 1 LASTPIN (10825 3250) $PN 1
J 0
(10815 3265);
DISPLAY 0.787234 (10815 3265);
PAINT ORANGE (10815 3265);
DISPLAY INVISIBLE (10815 3265);
FORCEPROP 1 LASTPIN (11025 3250) $PN 2
J 0
(11010 3265);
DISPLAY 0.787234 (11010 3265);
PAINT ORANGE (11010 3265);
DISPLAY INVISIBLE (11010 3265);
FORCEADD CAP_A..2
(11025 2250);
FORCEPROP 1 LAST LOCATION C1L13
J 1
(11025 2350);
DISPLAY 0.617021 (11025 2350);
PAINT AQUA (11025 2350);
FORCEPROP 1 LAST PART_NUMBER A36096-045
J 1
(11025 2300);
DISPLAY 0.617021 (11025 2300);
PAINT BLUE (11025 2300);
FORCEPROP 1 LAST VALUE 0.01UF
J 2
(11025 2150);
DISPLAY 0.617021 (11025 2150);
PAINT SKYBLUE (11025 2150);
FORCEPROP 1 LAST TOLERANCE 10%
J 2
(11025 2100);
DISPLAY 0.617021 (11025 2100);
PAINT SKYBLUE (11025 2100);
FORCEPROP 1 LAST PACK_TYPE 0402V
J 1
(11025 2050);
DISPLAY 0.617021 (11025 2050);
PAINT SKYBLUE (11025 2050);
FORCEPROP 1 LAST VOLTAGE 25V
J 0
(11025 2150);
DISPLAY 0.617021 (11025 2150);
PAINT SKYBLUE (11025 2150);
FORCEPROP 1 LAST MATERIAL X7R
J 0
(11025 2100);
DISPLAY 0.617021 (11025 2100);
PAINT SKYBLUE (11025 2100);
FORCEPROP 2 LAST CDS_LOCATION C1L13
J 1
(11025 2350);
DISPLAY 0.617021 (11025 2350);
PAINT AQUA (11025 2350);
DISPLAY INVISIBLE (11025 2350);
FORCEPROP 2 LAST BOM_COST ST_SATA
J 0
(10950 2400);
DISPLAY 1.361702 (10950 2400);
PAINT ORANGE (10950 2400);
DISPLAY INVISIBLE (10950 2400);
FORCEPROP 2 LAST CDS_LIB dev_discrete
J 0
(11025 2250);
PAINT ORANGE (11025 2250);
DISPLAY INVISIBLE (11025 2250);
FORCEPROP 2 LAST CDS_SEC 1
J 0
(11025 2500);
DISPLAY 1.021277 (11025 2500);
PAINT ORANGE (11025 2500);
DISPLAY INVISIBLE (11025 2500);
FORCEPROP 2 LAST $SEC 1
J 0
(11025 2500);
DISPLAY 0.680851 (11025 2500);
PAINT MONO (11025 2500);
DISPLAY INVISIBLE (11025 2500);
FORCEPROP 1 LAST PATH I14
J 0
(11025 2450);
DISPLAY 0.978723 (11025 2450);
PAINT WHITE (11025 2450);
DISPLAY INVISIBLE (11025 2450);
FORCEPROP 2 LAST ROOM ST_SATA
J 0
(10950 2400);
DISPLAY 1.361702 (10950 2400);
PAINT ORANGE (10950 2400);
DISPLAY INVISIBLE (10950 2400);
FORCEPROP 1 LASTPIN (10925 2250) $PN 1
J 0
(10915 2265);
DISPLAY 0.787234 (10915 2265);
PAINT ORANGE (10915 2265);
DISPLAY INVISIBLE (10915 2265);
FORCEPROP 1 LASTPIN (11125 2250) $PN 2
J 0
(11110 2265);
DISPLAY 0.787234 (11110 2265);
PAINT ORANGE (11110 2265);
DISPLAY INVISIBLE (11110 2265);
FORCEADD GND..1
(12250 2125);
FORCEPROP 3 LASTPIN (12250 2175) SIG_NAME GND\g
J 0
(12260 2185);
DISPLAY 0.659574 (12260 2185);
PAINT MONO (12260 2185);
DISPLAY INVISIBLE (12260 2185);
FORCEPROP 1 LAST VOLTAGE 0.0V
J 0
(12205 2082);
DISPLAY 0.340426 (12205 2082);
PAINT SKYBLUE (12205 2082);
DISPLAY INVISIBLE (12205 2082);
FORCEPROP 2 LAST BOM_COST ST_SATA
J 0
(12275 2200);
DISPLAY 1.361702 (12275 2200);
PAINT ORANGE (12275 2200);
DISPLAY INVISIBLE (12275 2200);
FORCEPROP 1 LAST SIZE 1B
J 0
(12325 2075);
DISPLAY 1.170213 (12325 2075);
PAINT AQUA (12325 2075);
DISPLAY INVISIBLE (12325 2075);
FORCEPROP 2 LAST CDS_LIB mstr_symbols
J 0
(12250 2125);
PAINT ORANGE (12250 2125);
DISPLAY INVISIBLE (12250 2125);
FORCEPROP 1 LAST BODY_TYPE PLUMBING
J 0
(12205 2082);
DISPLAY 0.340426 (12205 2082);
PAINT GREEN (12205 2082);
DISPLAY INVISIBLE (12205 2082);
FORCEPROP 1 LAST PATH I15
J 0
(12325 2125);
DISPLAY 0.872340 (12325 2125);
PAINT AQUA (12325 2125);
DISPLAY INVISIBLE (12325 2125);
FORCEPROP 2 LAST ROOM ST_SATA
J 0
(12275 2200);
DISPLAY 1.361702 (12275 2200);
PAINT ORANGE (12275 2200);
DISPLAY INVISIBLE (12275 2200);
FORCEPROP 1 LAST HDL_POWER GND
J 0
(12250 2275);
DISPLAY 1.170213 (12250 2275);
PAINT GREEN (12250 2275);
DISPLAY INVISIBLE (12250 2275);
FORCEADD TAP..1
(11950 2025);
FORCEPROP 3 LASTPIN (11900 2025) SIG_NAME SATA6G_TX_DP<3>
J 0
(11910 2035);
DISPLAY 0.659574 (11910 2035);
PAINT MONO (11910 2035);
DISPLAY INVISIBLE (11910 2035);
FORCEPROP 1 LASTPIN (11900 2025) BN 3
J 0
(11888 2033);
DISPLAY 0.617021 (11888 2033);
PAINT GREEN (11888 2033);
FORCEPROP 2 LAST CDS_LIB mstr_standard
J 0
(11950 2025);
PAINT ORANGE (11950 2025);
DISPLAY INVISIBLE (11950 2025);
FORCEPROP 1 LAST BODY_TYPE PLUMBING
J 0
(11950 2075);
DISPLAY 0.872340 (11950 2075);
PAINT GREEN (11950 2075);
DISPLAY INVISIBLE (11950 2075);
FORCEPROP 1 LAST HDL_TAP TRUE
J 0
(12275 1900);
DISPLAY 0.872340 (12275 1900);
PAINT ORANGE (12275 1900);
DISPLAY INVISIBLE (12275 1900);
FORCEPROP 1 LAST PATH I16
J 0
(11948 2025);
DISPLAY 0.872340 (11948 2025);
PAINT GREEN (11948 2025);
DISPLAY INVISIBLE (11948 2025);
FORCEADD TAP..1
(11800 1825);
FORCEPROP 3 LASTPIN (11750 1825) SIG_NAME SATA6G_TX_DN<3>
J 0
(11760 1835);
DISPLAY 0.659574 (11760 1835);
PAINT MONO (11760 1835);
DISPLAY INVISIBLE (11760 1835);
FORCEPROP 1 LASTPIN (11750 1825) BN 3
J 0
(11738 1833);
DISPLAY 0.617021 (11738 1833);
PAINT GREEN (11738 1833);
FORCEPROP 2 LAST CDS_LIB mstr_standard
J 0
(11800 1825);
PAINT ORANGE (11800 1825);
DISPLAY INVISIBLE (11800 1825);
FORCEPROP 1 LAST BODY_TYPE PLUMBING
J 0
(11800 1875);
DISPLAY 0.872340 (11800 1875);
PAINT GREEN (11800 1875);
DISPLAY INVISIBLE (11800 1875);
FORCEPROP 1 LAST HDL_TAP TRUE
J 0
(12125 1700);
DISPLAY 0.872340 (12125 1700);
PAINT ORANGE (12125 1700);
DISPLAY INVISIBLE (12125 1700);
FORCEPROP 1 LAST PATH I17
J 0
(11798 1825);
DISPLAY 0.872340 (11798 1825);
PAINT GREEN (11798 1825);
DISPLAY INVISIBLE (11798 1825);
FORCEADD CAP_A..2
(11025 1825);
FORCEPROP 1 LAST LOCATION C1L15
J 1
(11025 1925);
DISPLAY 0.617021 (11025 1925);
PAINT AQUA (11025 1925);
FORCEPROP 1 LAST PART_NUMBER A36096-045
J 1
(11025 1875);
DISPLAY 0.617021 (11025 1875);
PAINT BLUE (11025 1875);
FORCEPROP 1 LAST VALUE 0.01UF
J 2
(11025 1725);
DISPLAY 0.617021 (11025 1725);
PAINT SKYBLUE (11025 1725);
FORCEPROP 1 LAST TOLERANCE 10%
J 2
(11025 1675);
DISPLAY 0.617021 (11025 1675);
PAINT SKYBLUE (11025 1675);
FORCEPROP 1 LAST PACK_TYPE 0402V
J 1
(11025 1625);
DISPLAY 0.617021 (11025 1625);
PAINT SKYBLUE (11025 1625);
FORCEPROP 1 LAST VOLTAGE 25V
J 0
(11025 1725);
DISPLAY 0.617021 (11025 1725);
PAINT SKYBLUE (11025 1725);
FORCEPROP 1 LAST MATERIAL X7R
J 0
(11025 1675);
DISPLAY 0.617021 (11025 1675);
PAINT SKYBLUE (11025 1675);
FORCEPROP 2 LAST CDS_LOCATION C1L15
J 1
(11025 1925);
DISPLAY 0.617021 (11025 1925);
PAINT AQUA (11025 1925);
DISPLAY INVISIBLE (11025 1925);
FORCEPROP 2 LAST BOM_COST ST_SATA
J 0
(10950 1975);
DISPLAY 1.361702 (10950 1975);
PAINT ORANGE (10950 1975);
DISPLAY INVISIBLE (10950 1975);
FORCEPROP 2 LAST CDS_LIB dev_discrete
J 0
(11025 1825);
PAINT ORANGE (11025 1825);
DISPLAY INVISIBLE (11025 1825);
FORCEPROP 2 LAST CDS_SEC 1
J 0
(11025 2075);
DISPLAY 1.021277 (11025 2075);
PAINT ORANGE (11025 2075);
DISPLAY INVISIBLE (11025 2075);
FORCEPROP 2 LAST $SEC 1
J 0
(11025 2075);
DISPLAY 0.680851 (11025 2075);
PAINT MONO (11025 2075);
DISPLAY INVISIBLE (11025 2075);
FORCEPROP 1 LAST PATH I18
J 0
(11025 2025);
DISPLAY 0.978723 (11025 2025);
PAINT WHITE (11025 2025);
DISPLAY INVISIBLE (11025 2025);
FORCEPROP 2 LAST ROOM ST_SATA
J 0
(10950 1975);
DISPLAY 1.361702 (10950 1975);
PAINT ORANGE (10950 1975);
DISPLAY INVISIBLE (10950 1975);
FORCEPROP 1 LASTPIN (10925 1825) $PN 1
J 0
(10915 1840);
DISPLAY 0.787234 (10915 1840);
PAINT ORANGE (10915 1840);
DISPLAY INVISIBLE (10915 1840);
FORCEPROP 1 LASTPIN (11125 1825) $PN 2
J 0
(11110 1840);
DISPLAY 0.787234 (11110 1840);
PAINT ORANGE (11110 1840);
DISPLAY INVISIBLE (11110 1840);
FORCEADD CAP_A..2
(10750 2475);
FORCEPROP 1 LAST LOCATION C1L12
J 1
(10750 2575);
DISPLAY 0.617021 (10750 2575);
PAINT AQUA (10750 2575);
FORCEPROP 1 LAST PART_NUMBER A36096-045
J 1
(10750 2525);
DISPLAY 0.617021 (10750 2525);
PAINT BLUE (10750 2525);
FORCEPROP 1 LAST VALUE 0.01UF
J 2
(10750 2375);
DISPLAY 0.617021 (10750 2375);
PAINT SKYBLUE (10750 2375);
FORCEPROP 1 LAST TOLERANCE 10%
J 2
(10750 2325);
DISPLAY 0.617021 (10750 2325);
PAINT SKYBLUE (10750 2325);
FORCEPROP 1 LAST PACK_TYPE 0402V
J 1
(10750 2275);
DISPLAY 0.617021 (10750 2275);
PAINT SKYBLUE (10750 2275);
FORCEPROP 1 LAST VOLTAGE 25V
J 0
(10750 2375);
DISPLAY 0.617021 (10750 2375);
PAINT SKYBLUE (10750 2375);
FORCEPROP 1 LAST MATERIAL X7R
J 0
(10750 2325);
DISPLAY 0.617021 (10750 2325);
PAINT SKYBLUE (10750 2325);
FORCEPROP 2 LAST CDS_LOCATION C1L12
J 1
(10750 2575);
DISPLAY 0.617021 (10750 2575);
PAINT AQUA (10750 2575);
DISPLAY INVISIBLE (10750 2575);
FORCEPROP 2 LAST BOM_COST ST_SATA
J 0
(10600 2625);
DISPLAY 1.361702 (10600 2625);
PAINT ORANGE (10600 2625);
DISPLAY INVISIBLE (10600 2625);
FORCEPROP 2 LAST CDS_LIB dev_discrete
J 0
(10750 2475);
PAINT ORANGE (10750 2475);
DISPLAY INVISIBLE (10750 2475);
FORCEPROP 2 LAST CDS_SEC 1
J 0
(10750 2725);
DISPLAY 1.021277 (10750 2725);
PAINT ORANGE (10750 2725);
DISPLAY INVISIBLE (10750 2725);
FORCEPROP 2 LAST $SEC 1
J 0
(10750 2725);
DISPLAY 0.680851 (10750 2725);
PAINT MONO (10750 2725);
DISPLAY INVISIBLE (10750 2725);
FORCEPROP 1 LAST PATH I19
J 0
(10750 2675);
DISPLAY 0.978723 (10750 2675);
PAINT WHITE (10750 2675);
DISPLAY INVISIBLE (10750 2675);
FORCEPROP 2 LAST ROOM ST_SATA
J 0
(10600 2625);
DISPLAY 1.361702 (10600 2625);
PAINT ORANGE (10600 2625);
DISPLAY INVISIBLE (10600 2625);
FORCEPROP 1 LASTPIN (10650 2475) $PN 1
J 0
(10640 2490);
DISPLAY 0.787234 (10640 2490);
PAINT ORANGE (10640 2490);
DISPLAY INVISIBLE (10640 2490);
FORCEPROP 1 LASTPIN (10850 2475) $PN 2
J 0
(10835 2490);
DISPLAY 0.787234 (10835 2490);
PAINT ORANGE (10835 2490);
DISPLAY INVISIBLE (10835 2490);
FORCEADD OFFPAGE..1
(11100 4425);
FORCEPROP 2 LAST $XR0 116 
J 0
(10848 4425);
DISPLAY 0.638298 (10848 4425);
PAINT MONO (10848 4425);
FORCEPROP 2 LAST CDS_LIB mstr_standard
J 0
(11100 4425);
PAINT ORANGE (11100 4425);
DISPLAY INVISIBLE (11100 4425);
FORCEPROP 1 LAST OFFPAGE TRUE
J 0
(11425 4300);
DISPLAY 0.872340 (11425 4300);
PAINT GREEN (11425 4300);
DISPLAY INVISIBLE (11425 4300);
FORCEPROP 1 LAST COMMENT_BODY TRUE
J 0
(11225 4325);
DISPLAY 0.872340 (11225 4325);
PAINT GREEN (11225 4325);
DISPLAY INVISIBLE (11225 4325);
FORCEPROP 2 LAST PATH I2
J 0
(10825 4475);
DISPLAY 1.021277 (10825 4475);
PAINT ORANGE (10825 4475);
DISPLAY INVISIBLE (10825 4475);
FORCEADD CAP_A..2
(10750 2025);
FORCEPROP 1 LAST LOCATION C1L14
J 1
(10750 2125);
DISPLAY 0.617021 (10750 2125);
PAINT AQUA (10750 2125);
FORCEPROP 1 LAST PART_NUMBER A36096-045
J 1
(10750 2075);
DISPLAY 0.617021 (10750 2075);
PAINT BLUE (10750 2075);
FORCEPROP 1 LAST VALUE 0.01UF
J 2
(10750 1925);
DISPLAY 0.617021 (10750 1925);
PAINT SKYBLUE (10750 1925);
FORCEPROP 1 LAST TOLERANCE 10%
J 2
(10750 1875);
DISPLAY 0.617021 (10750 1875);
PAINT SKYBLUE (10750 1875);
FORCEPROP 1 LAST PACK_TYPE 0402V
J 1
(10750 1825);
DISPLAY 0.617021 (10750 1825);
PAINT SKYBLUE (10750 1825);
FORCEPROP 1 LAST VOLTAGE 25V
J 0
(10750 1925);
DISPLAY 0.617021 (10750 1925);
PAINT SKYBLUE (10750 1925);
FORCEPROP 1 LAST MATERIAL X7R
J 0
(10750 1875);
DISPLAY 0.617021 (10750 1875);
PAINT SKYBLUE (10750 1875);
FORCEPROP 2 LAST CDS_LOCATION C1L14
J 1
(10750 2125);
DISPLAY 0.617021 (10750 2125);
PAINT AQUA (10750 2125);
DISPLAY INVISIBLE (10750 2125);
FORCEPROP 2 LAST BOM_COST ST_SATA
J 0
(10650 2175);
DISPLAY 1.361702 (10650 2175);
PAINT ORANGE (10650 2175);
DISPLAY INVISIBLE (10650 2175);
FORCEPROP 2 LAST CDS_LIB dev_discrete
J 0
(10750 2025);
PAINT ORANGE (10750 2025);
DISPLAY INVISIBLE (10750 2025);
FORCEPROP 2 LAST CDS_SEC 1
J 0
(10750 2275);
DISPLAY 1.021277 (10750 2275);
PAINT ORANGE (10750 2275);
DISPLAY INVISIBLE (10750 2275);
FORCEPROP 2 LAST $SEC 1
J 0
(10750 2275);
DISPLAY 0.680851 (10750 2275);
PAINT MONO (10750 2275);
DISPLAY INVISIBLE (10750 2275);
FORCEPROP 1 LAST PATH I20
J 0
(10750 2225);
DISPLAY 0.978723 (10750 2225);
PAINT WHITE (10750 2225);
DISPLAY INVISIBLE (10750 2225);
FORCEPROP 2 LAST ROOM ST_SATA
J 0
(10650 2175);
DISPLAY 1.361702 (10650 2175);
PAINT ORANGE (10650 2175);
DISPLAY INVISIBLE (10650 2175);
FORCEPROP 1 LASTPIN (10650 2025) $PN 1
J 0
(10640 2040);
DISPLAY 0.787234 (10640 2040);
PAINT ORANGE (10640 2040);
DISPLAY INVISIBLE (10640 2040);
FORCEPROP 1 LASTPIN (10850 2025) $PN 2
J 0
(10835 2040);
DISPLAY 0.787234 (10835 2040);
PAINT ORANGE (10835 2040);
DISPLAY INVISIBLE (10835 2040);
FORCEADD GND..1
(9425 1850);
FORCEPROP 3 LASTPIN (9425 1900) SIG_NAME GND\g
J 0
(9435 1910);
DISPLAY 0.659574 (9435 1910);
PAINT MONO (9435 1910);
DISPLAY INVISIBLE (9435 1910);
FORCEPROP 1 LAST VOLTAGE 0.0V
J 0
(9380 1807);
DISPLAY 0.340426 (9380 1807);
PAINT SKYBLUE (9380 1807);
DISPLAY INVISIBLE (9380 1807);
FORCEPROP 2 LAST CDS_LIB mstr_symbols
J 0
(9425 1850);
PAINT ORANGE (9425 1850);
DISPLAY INVISIBLE (9425 1850);
FORCEPROP 1 LAST SIZE 1B
J 0
(9500 1800);
DISPLAY 1.170213 (9500 1800);
PAINT AQUA (9500 1800);
DISPLAY INVISIBLE (9500 1800);
FORCEPROP 2 LAST BOM_COST ST_SATA
J 0
(9450 1925);
DISPLAY 1.361702 (9450 1925);
PAINT ORANGE (9450 1925);
DISPLAY INVISIBLE (9450 1925);
FORCEPROP 1 LAST BODY_TYPE PLUMBING
J 0
(9380 1807);
DISPLAY 0.340426 (9380 1807);
PAINT GREEN (9380 1807);
DISPLAY INVISIBLE (9380 1807);
FORCEPROP 1 LAST PATH I21
J 0
(9500 1850);
DISPLAY 0.872340 (9500 1850);
PAINT AQUA (9500 1850);
DISPLAY INVISIBLE (9500 1850);
FORCEPROP 2 LAST ROOM ST_SATA
J 0
(9450 1925);
DISPLAY 1.361702 (9450 1925);
PAINT ORANGE (9450 1925);
DISPLAY INVISIBLE (9450 1925);
FORCEPROP 1 LAST HDL_POWER GND
J 0
(9425 2000);
DISPLAY 1.170213 (9425 2000);
PAINT GREEN (9425 2000);
DISPLAY INVISIBLE (9425 2000);
FORCEADD OFFPAGE..2
(6700 4550);
FORCEPROP 2 LAST $XR0 116 
J 0
(6889 4550);
DISPLAY 0.638298 (6889 4550);
PAINT MONO (6889 4550);
FORCEPROP 2 LAST CDS_LIB mstr_standard
J 0
(6700 4550);
PAINT ORANGE (6700 4550);
DISPLAY INVISIBLE (6700 4550);
FORCEPROP 1 LAST OFFPAGE TRUE
J 0
(7025 4425);
DISPLAY 0.872340 (7025 4425);
PAINT GREEN (7025 4425);
DISPLAY INVISIBLE (7025 4425);
FORCEPROP 1 LAST COMMENT_BODY TRUE
J 0
(6655 4455);
DISPLAY 0.872340 (6655 4455);
PAINT GREEN (6655 4455);
DISPLAY INVISIBLE (6655 4455);
FORCEPROP 2 LAST PATH I22
J 0
(6900 4600);
DISPLAY 1.021277 (6900 4600);
PAINT ORANGE (6900 4600);
DISPLAY INVISIBLE (6900 4600);
FORCEADD OFFPAGE..2
(6700 4400);
FORCEPROP 2 LAST $XR0 116 
J 0
(6889 4400);
DISPLAY 0.638298 (6889 4400);
PAINT MONO (6889 4400);
FORCEPROP 2 LAST CDS_LIB mstr_standard
J 0
(6700 4400);
PAINT ORANGE (6700 4400);
DISPLAY INVISIBLE (6700 4400);
FORCEPROP 1 LAST OFFPAGE TRUE
J 0
(7025 4275);
DISPLAY 0.872340 (7025 4275);
PAINT GREEN (7025 4275);
DISPLAY INVISIBLE (7025 4275);
FORCEPROP 1 LAST COMMENT_BODY TRUE
J 0
(6655 4305);
DISPLAY 0.872340 (6655 4305);
PAINT GREEN (6655 4305);
DISPLAY INVISIBLE (6655 4305);
FORCEPROP 2 LAST PATH I23
J 0
(6900 4450);
DISPLAY 1.021277 (6900 4450);
PAINT ORANGE (6900 4450);
DISPLAY INVISIBLE (6900 4450);
FORCEADD P3V3..1
(7250 3950);
FORCEPROP 3 LASTPIN (7250 3900) SIG_NAME P3V3\g
J 0
(7260 3910);
DISPLAY 0.659574 (7260 3910);
PAINT MONO (7260 3910);
DISPLAY INVISIBLE (7260 3910);
FORCEPROP 1 LAST VOLTAGE 3.3V
J 0
(7205 3907);
DISPLAY 0.340426 (7205 3907);
PAINT SKYBLUE (7205 3907);
DISPLAY INVISIBLE (7205 3907);
FORCEPROP 2 LAST CDS_LIB mstr_symbols
J 0
(7250 3950);
PAINT ORANGE (7250 3950);
DISPLAY INVISIBLE (7250 3950);
FORCEPROP 1 LAST SIZE 1B
J 0
(7295 3972);
DISPLAY 0.446809 (7295 3972);
PAINT GREEN (7295 3972);
DISPLAY INVISIBLE (7295 3972);
FORCEPROP 2 LAST BOM_COST ST_SATA
J 0
(7350 4050);
DISPLAY 1.361702 (7350 4050);
PAINT ORANGE (7350 4050);
DISPLAY INVISIBLE (7350 4050);
FORCEPROP 1 LAST BODY_TYPE PLUMBING
J 0
(7205 3907);
DISPLAY 0.446809 (7205 3907);
PAINT GREEN (7205 3907);
DISPLAY INVISIBLE (7205 3907);
FORCEPROP 1 LAST PATH I24
J 0
(7295 3952);
DISPLAY 0.340426 (7295 3952);
PAINT GREEN (7295 3952);
DISPLAY INVISIBLE (7295 3952);
FORCEPROP 2 LAST ROOM ST_SATA
J 0
(7350 4050);
DISPLAY 1.361702 (7350 4050);
PAINT ORANGE (7350 4050);
DISPLAY INVISIBLE (7350 4050);
FORCEPROP 1 LAST HDL_POWER P3V3
J 0
(6925 3825);
DISPLAY 1.170213 (6925 3825);
PAINT GREEN (6925 3825);
DISPLAY INVISIBLE (6925 3825);
FORCEADD RES..2
(7250 3600);
FORCEPROP 1 LAST LOCATION R1L1
J 0
(7295 3725);
DISPLAY 0.617021 (7295 3725);
PAINT AQUA (7295 3725);
FORCEPROP 1 LAST PART_NUMBER G21796-001
J 0
(7290 3475);
DISPLAY 0.617021 (7290 3475);
PAINT BLUE (7290 3475);
FORCEPROP 1 LAST VALUE 2.0K
J 0
(7295 3675);
DISPLAY 0.617021 (7295 3675);
PAINT SKYBLUE (7295 3675);
FORCEPROP 1 LAST TOLERANCE 1%
J 0
(7295 3625);
DISPLAY 0.617021 (7295 3625);
PAINT SKYBLUE (7295 3625);
FORCEPROP 1 LAST PACK_TYPE 0402
J 0
(7290 3425);
DISPLAY 0.617021 (7290 3425);
PAINT SKYBLUE (7290 3425);
FORCEPROP 1 LAST MATERIAL CHIP
J 0
(7290 3525);
DISPLAY 0.617021 (7290 3525);
PAINT SKYBLUE (7290 3525);
FORCEPROP 1 LAST WATTAGE 1/16W
J 0
(7290 3575);
DISPLAY 0.617021 (7290 3575);
PAINT SKYBLUE (7290 3575);
FORCEPROP 2 LAST BOM_COST ST_SATA
J 0
(7300 3775);
DISPLAY 1.361702 (7300 3775);
PAINT ORANGE (7300 3775);
DISPLAY INVISIBLE (7300 3775);
FORCEPROP 2 LAST CDS_LIB mstr_discrete
J 0
(7250 3600);
PAINT ORANGE (7250 3600);
DISPLAY INVISIBLE (7250 3600);
FORCEPROP 2 LAST CDS_SEC 1
J 0
(7300 3825);
DISPLAY 1.021277 (7300 3825);
PAINT ORANGE (7300 3825);
DISPLAY INVISIBLE (7300 3825);
FORCEPROP 2 LAST $SEC 1
J 0
(7300 3825);
DISPLAY 0.680851 (7300 3825);
PAINT MONO (7300 3825);
DISPLAY INVISIBLE (7300 3825);
FORCEPROP 2 LAST CDS_LOCATION R1L1
J 0
(7295 3725);
DISPLAY 0.617021 (7295 3725);
PAINT AQUA (7295 3725);
DISPLAY INVISIBLE (7295 3725);
FORCEPROP 1 LAST PATH I25
J 0
(7300 3775);
DISPLAY 0.978723 (7300 3775);
PAINT WHITE (7300 3775);
DISPLAY INVISIBLE (7300 3775);
FORCEPROP 2 LAST ROOM ST_SATA
J 0
(7300 3775);
DISPLAY 1.361702 (7300 3775);
PAINT ORANGE (7300 3775);
DISPLAY INVISIBLE (7300 3775);
FORCEPROP 1 LASTPIN (7250 3500) $PN 2
J 0
(7255 3510);
DISPLAY 0.787234 (7255 3510);
PAINT ORANGE (7255 3510);
DISPLAY INVISIBLE (7255 3510);
FORCEPROP 1 LASTPIN (7250 3700) $PN 1
J 0
(7255 3662);
DISPLAY 0.787234 (7255 3662);
PAINT ORANGE (7255 3662);
DISPLAY INVISIBLE (7255 3662);
FORCEADD CONN36_G97614001..1
(8650 2725);
FORCEPROP 1 LAST LOCATION J8A2
J 0
(8100 3625);
DISPLAY 0.617021 (8100 3625);
PAINT AQUA (8100 3625);
FORCEPROP 1 LAST PART_NUMBER G97614-001
J 0
(8100 1825);
DISPLAY 0.617021 (8100 1825);
PAINT BLUE (8100 1825);
FORCEPROP 1 LAST MATERIAL CONN
J 0
(8100 3575);
DISPLAY 0.617021 (8100 3575);
PAINT SKYBLUE (8100 3575);
FORCEPROP 2 LASTPIN (9250 2225) $PN C7
J 0
(9260 2235);
DISPLAY 0.617021 (9260 2235);
PAINT ORANGE (9260 2235);
FORCEPROP 2 LASTPIN (9250 2175) $PN C8
J 0
(9260 2185);
DISPLAY 0.617021 (9260 2185);
PAINT ORANGE (9260 2185);
FORCEPROP 2 LASTPIN (9250 2475) $PN D7
J 0
(9260 2485);
DISPLAY 0.617021 (9260 2485);
PAINT ORANGE (9260 2485);
FORCEPROP 2 LASTPIN (9250 2425) $PN D8
J 0
(9260 2435);
DISPLAY 0.617021 (9260 2435);
PAINT ORANGE (9260 2435);
FORCEPROP 2 LASTPIN (9250 3075) $PN C4
J 0
(9260 3085);
DISPLAY 0.617021 (9260 3085);
PAINT ORANGE (9260 3085);
FORCEPROP 2 LASTPIN (9250 3025) $PN C5
J 0
(9260 3035);
DISPLAY 0.617021 (9260 3035);
PAINT ORANGE (9260 3035);
FORCEPROP 2 LASTPIN (9250 3325) $PN D4
J 0
(9260 3335);
DISPLAY 0.617021 (9260 3335);
PAINT ORANGE (9260 3335);
FORCEPROP 2 LASTPIN (9250 3275) $PN D5
J 0
(9260 3285);
DISPLAY 0.617021 (9260 3285);
PAINT ORANGE (9260 3285);
FORCEPROP 2 LASTPIN (8050 2825) $PN A1
J 2
(8040 2835);
DISPLAY 0.617021 (8040 2835);
PAINT ORANGE (8040 2835);
FORCEPROP 2 LASTPIN (9250 2675) $PN D2
J 0
(9260 2685);
DISPLAY 0.617021 (9260 2685);
PAINT ORANGE (9260 2685);
FORCEPROP 2 LASTPIN (8050 2675) $PN D1
J 2
(8040 2685);
DISPLAY 0.617021 (8040 2685);
PAINT ORANGE (8040 2685);
FORCEPROP 2 LASTPIN (8050 2725) $PN C1
J 2
(8040 2735);
DISPLAY 0.617021 (8040 2735);
PAINT ORANGE (8040 2735);
FORCEPROP 2 LASTPIN (8050 2775) $PN B1
J 2
(8040 2785);
DISPLAY 0.617021 (8040 2785);
PAINT ORANGE (8040 2785);
FORCEPROP 2 LASTPIN (9250 2725) $PN C2
J 0
(9260 2735);
DISPLAY 0.617021 (9260 2735);
PAINT ORANGE (9260 2735);
FORCEPROP 2 LASTPIN (9250 2775) $PN B2
J 0
(9260 2785);
DISPLAY 0.617021 (9260 2785);
PAINT ORANGE (9260 2785);
FORCEPROP 2 LASTPIN (9250 2825) $PN A2
J 0
(9260 2835);
DISPLAY 0.617021 (9260 2835);
PAINT ORANGE (9260 2835);
FORCEPROP 2 LASTPIN (8050 2225) $PN A7
J 2
(8040 2235);
DISPLAY 0.617021 (8040 2235);
PAINT ORANGE (8040 2235);
FORCEPROP 2 LASTPIN (8050 2175) $PN A8
J 2
(8040 2185);
DISPLAY 0.617021 (8040 2185);
PAINT ORANGE (8040 2185);
FORCEPROP 2 LASTPIN (8050 2475) $PN B7
J 2
(8040 2485);
DISPLAY 0.617021 (8040 2485);
PAINT ORANGE (8040 2485);
FORCEPROP 2 LASTPIN (8050 2425) $PN B8
J 2
(8040 2435);
DISPLAY 0.617021 (8040 2435);
PAINT ORANGE (8040 2435);
FORCEPROP 2 LASTPIN (8050 3075) $PN A4
J 2
(8040 3085);
DISPLAY 0.617021 (8040 3085);
PAINT ORANGE (8040 3085);
FORCEPROP 2 LASTPIN (8050 3025) $PN A5
J 2
(8040 3035);
DISPLAY 0.617021 (8040 3035);
PAINT ORANGE (8040 3035);
FORCEPROP 2 LASTPIN (8050 3325) $PN B4
J 2
(8040 3335);
DISPLAY 0.617021 (8040 3335);
PAINT ORANGE (8040 3335);
FORCEPROP 2 LASTPIN (8050 3275) $PN B5
J 2
(8040 3285);
DISPLAY 0.617021 (8040 3285);
PAINT ORANGE (8040 3285);
FORCEPROP 2 LASTPIN (9250 2075) $PN D9
J 0
(9260 2085);
DISPLAY 0.617021 (9260 2085);
PAINT ORANGE (9260 2085);
FORCEPROP 2 LASTPIN (9250 2325) $PN D6
J 0
(9260 2335);
DISPLAY 0.617021 (9260 2335);
PAINT ORANGE (9260 2335);
FORCEPROP 2 LASTPIN (9250 2575) $PN D3
J 0
(9260 2585);
DISPLAY 0.617021 (9260 2585);
PAINT ORANGE (9260 2585);
FORCEPROP 2 LASTPIN (9250 2925) $PN C9
J 0
(9260 2935);
DISPLAY 0.617021 (9260 2935);
PAINT ORANGE (9260 2935);
FORCEPROP 2 LASTPIN (9250 3175) $PN C6
J 0
(9260 3185);
DISPLAY 0.617021 (9260 3185);
PAINT ORANGE (9260 3185);
FORCEPROP 2 LASTPIN (9250 3425) $PN C3
J 0
(9260 3435);
DISPLAY 0.617021 (9260 3435);
PAINT ORANGE (9260 3435);
FORCEPROP 2 LASTPIN (8050 2075) $PN B9
J 2
(8040 2085);
DISPLAY 0.617021 (8040 2085);
PAINT ORANGE (8040 2085);
FORCEPROP 2 LASTPIN (8050 2325) $PN B6
J 2
(8040 2335);
DISPLAY 0.617021 (8040 2335);
PAINT ORANGE (8040 2335);
FORCEPROP 2 LASTPIN (8050 2575) $PN B3
J 2
(8040 2585);
DISPLAY 0.617021 (8040 2585);
PAINT ORANGE (8040 2585);
FORCEPROP 2 LASTPIN (8050 2925) $PN A9
J 2
(8040 2935);
DISPLAY 0.617021 (8040 2935);
PAINT ORANGE (8040 2935);
FORCEPROP 2 LASTPIN (8050 3175) $PN A6
J 2
(8040 3185);
DISPLAY 0.617021 (8040 3185);
PAINT ORANGE (8040 3185);
FORCEPROP 2 LASTPIN (8050 3425) $PN A3
J 2
(8040 3435);
DISPLAY 0.617021 (8040 3435);
PAINT ORANGE (8040 3435);
FORCEPROP 1 LAST PACK_TYPE CP
J 0
(8100 3675);
PAINT SKYBLUE (8100 3675);
DISPLAY INVISIBLE (8100 3675);
FORCEPROP 2 LAST BOM_COST ST_SATA
J 0
(8050 3675);
DISPLAY 1.361702 (8050 3675);
PAINT ORANGE (8050 3675);
DISPLAY INVISIBLE (8050 3675);
FORCEPROP 2 LAST CDS_LIB mstr_conn
J 0
(8650 2725);
PAINT ORANGE (8650 2725);
DISPLAY INVISIBLE (8650 2725);
FORCEPROP 2 LAST CDS_SEC 1
J 0
(8650 3675);
DISPLAY 1.021277 (8650 3675);
PAINT ORANGE (8650 3675);
DISPLAY INVISIBLE (8650 3675);
FORCEPROP 2 LAST $SEC 1
J 0
(8650 3675);
DISPLAY 0.680851 (8650 3675);
PAINT MONO (8650 3675);
DISPLAY INVISIBLE (8650 3675);
FORCEPROP 2 LAST CDS_LOCATION J8A2
J 0
(8100 3625);
DISPLAY 0.617021 (8100 3625);
PAINT AQUA (8100 3625);
DISPLAY INVISIBLE (8100 3625);
FORCEPROP 1 LAST PATH I26
J 0
(8650 3625);
PAINT GREEN (8650 3625);
DISPLAY INVISIBLE (8650 3625);
FORCEPROP 2 LAST ROOM ST_SATA
J 0
(8050 3675);
DISPLAY 1.361702 (8050 3675);
PAINT ORANGE (8050 3675);
DISPLAY INVISIBLE (8050 3675);
FORCEADD GND..1
(7850 1875);
FORCEPROP 3 LASTPIN (7850 1925) SIG_NAME GND\g
J 0
(7860 1935);
DISPLAY 0.659574 (7860 1935);
PAINT MONO (7860 1935);
DISPLAY INVISIBLE (7860 1935);
FORCEPROP 1 LAST VOLTAGE 0.0V
J 0
(7805 1832);
DISPLAY 0.340426 (7805 1832);
PAINT SKYBLUE (7805 1832);
DISPLAY INVISIBLE (7805 1832);
FORCEPROP 2 LAST CDS_LIB mstr_symbols
J 0
(7850 1875);
PAINT ORANGE (7850 1875);
DISPLAY INVISIBLE (7850 1875);
FORCEPROP 2 LAST BOM_COST ST_SATA
J 0
(7875 1950);
DISPLAY 1.361702 (7875 1950);
PAINT ORANGE (7875 1950);
DISPLAY INVISIBLE (7875 1950);
FORCEPROP 1 LAST SIZE 1B
J 0
(7925 1825);
DISPLAY 1.170213 (7925 1825);
PAINT AQUA (7925 1825);
DISPLAY INVISIBLE (7925 1825);
FORCEPROP 1 LAST BODY_TYPE PLUMBING
J 0
(7805 1832);
DISPLAY 0.340426 (7805 1832);
PAINT GREEN (7805 1832);
DISPLAY INVISIBLE (7805 1832);
FORCEPROP 1 LAST PATH I27
J 0
(7925 1875);
DISPLAY 0.872340 (7925 1875);
PAINT AQUA (7925 1875);
DISPLAY INVISIBLE (7925 1875);
FORCEPROP 2 LAST ROOM ST_SATA
J 0
(7875 1950);
DISPLAY 1.361702 (7875 1950);
PAINT ORANGE (7875 1950);
DISPLAY INVISIBLE (7875 1950);
FORCEPROP 1 LAST HDL_POWER GND
J 0
(7850 2025);
DISPLAY 1.170213 (7850 2025);
PAINT GREEN (7850 2025);
DISPLAY INVISIBLE (7850 2025);
FORCEADD CAP_A..2
(6525 3675);
FORCEPROP 1 LAST LOCATION C2L30
J 1
(6525 3775);
DISPLAY 0.617021 (6525 3775);
PAINT AQUA (6525 3775);
FORCEPROP 1 LAST PART_NUMBER A36096-045
J 1
(6525 3725);
DISPLAY 0.617021 (6525 3725);
PAINT BLUE (6525 3725);
FORCEPROP 1 LAST VALUE 0.01UF
J 2
(6525 3575);
DISPLAY 0.617021 (6525 3575);
PAINT SKYBLUE (6525 3575);
FORCEPROP 1 LAST TOLERANCE 10%
J 2
(6525 3525);
DISPLAY 0.617021 (6525 3525);
PAINT SKYBLUE (6525 3525);
FORCEPROP 1 LAST PACK_TYPE 0402V
J 1
(6525 3475);
DISPLAY 0.617021 (6525 3475);
PAINT SKYBLUE (6525 3475);
FORCEPROP 1 LAST VOLTAGE 25V
J 0
(6525 3575);
DISPLAY 0.617021 (6525 3575);
PAINT SKYBLUE (6525 3575);
FORCEPROP 1 LAST MATERIAL X7R
J 0
(6525 3525);
DISPLAY 0.617021 (6525 3525);
PAINT SKYBLUE (6525 3525);
FORCEPROP 2 LAST CDS_LOCATION C2L30
J 1
(6525 3775);
DISPLAY 0.617021 (6525 3775);
PAINT AQUA (6525 3775);
DISPLAY INVISIBLE (6525 3775);
FORCEPROP 2 LAST BOM_COST ST_SATA
J 0
(6475 3775);
DISPLAY 1.361702 (6475 3775);
PAINT ORANGE (6475 3775);
DISPLAY INVISIBLE (6475 3775);
FORCEPROP 2 LAST CDS_LIB dev_discrete
J 0
(6525 3675);
PAINT ORANGE (6525 3675);
DISPLAY INVISIBLE (6525 3675);
FORCEPROP 2 LAST CDS_SEC 1
J 0
(6525 3925);
DISPLAY 1.021277 (6525 3925);
PAINT ORANGE (6525 3925);
DISPLAY INVISIBLE (6525 3925);
FORCEPROP 2 LAST $SEC 1
J 0
(6525 3925);
DISPLAY 0.680851 (6525 3925);
PAINT MONO (6525 3925);
DISPLAY INVISIBLE (6525 3925);
FORCEPROP 1 LAST PATH I28
J 0
(6525 3875);
DISPLAY 0.978723 (6525 3875);
PAINT WHITE (6525 3875);
DISPLAY INVISIBLE (6525 3875);
FORCEPROP 2 LAST ROOM ST_SATA
J 0
(6475 3825);
DISPLAY 1.361702 (6475 3825);
PAINT ORANGE (6475 3825);
DISPLAY INVISIBLE (6475 3825);
FORCEPROP 1 LASTPIN (6425 3675) $PN 1
J 0
(6415 3690);
DISPLAY 0.787234 (6415 3690);
PAINT ORANGE (6415 3690);
DISPLAY INVISIBLE (6415 3690);
FORCEPROP 1 LASTPIN (6625 3675) $PN 2
J 0
(6610 3690);
DISPLAY 0.787234 (6610 3690);
PAINT ORANGE (6610 3690);
DISPLAY INVISIBLE (6610 3690);
FORCEADD CAP_A..2
(6225 3450);
FORCEPROP 1 LAST LOCATION C2L31
J 1
(6225 3550);
DISPLAY 0.617021 (6225 3550);
PAINT AQUA (6225 3550);
FORCEPROP 1 LAST PART_NUMBER A36096-045
J 1
(6225 3500);
DISPLAY 0.617021 (6225 3500);
PAINT BLUE (6225 3500);
FORCEPROP 1 LAST VALUE 0.01UF
J 2
(6225 3350);
DISPLAY 0.617021 (6225 3350);
PAINT SKYBLUE (6225 3350);
FORCEPROP 1 LAST TOLERANCE 10%
J 2
(6225 3300);
DISPLAY 0.617021 (6225 3300);
PAINT SKYBLUE (6225 3300);
FORCEPROP 1 LAST PACK_TYPE 0402V
J 1
(6225 3250);
DISPLAY 0.617021 (6225 3250);
PAINT SKYBLUE (6225 3250);
FORCEPROP 1 LAST VOLTAGE 25V
J 0
(6225 3350);
DISPLAY 0.617021 (6225 3350);
PAINT SKYBLUE (6225 3350);
FORCEPROP 1 LAST MATERIAL X7R
J 0
(6225 3300);
DISPLAY 0.617021 (6225 3300);
PAINT SKYBLUE (6225 3300);
FORCEPROP 2 LAST CDS_LOCATION C2L31
J 1
(6225 3550);
DISPLAY 0.617021 (6225 3550);
PAINT AQUA (6225 3550);
DISPLAY INVISIBLE (6225 3550);
FORCEPROP 2 LAST BOM_COST ST_SATA
J 0
(6175 3550);
DISPLAY 1.361702 (6175 3550);
PAINT ORANGE (6175 3550);
DISPLAY INVISIBLE (6175 3550);
FORCEPROP 2 LAST CDS_LIB dev_discrete
J 0
(6225 3450);
PAINT ORANGE (6225 3450);
DISPLAY INVISIBLE (6225 3450);
FORCEPROP 2 LAST CDS_SEC 1
J 0
(6225 3700);
DISPLAY 1.021277 (6225 3700);
PAINT ORANGE (6225 3700);
DISPLAY INVISIBLE (6225 3700);
FORCEPROP 2 LAST $SEC 1
J 0
(6225 3700);
DISPLAY 0.680851 (6225 3700);
PAINT MONO (6225 3700);
DISPLAY INVISIBLE (6225 3700);
FORCEPROP 1 LAST PATH I29
J 0
(6225 3650);
DISPLAY 0.978723 (6225 3650);
PAINT WHITE (6225 3650);
DISPLAY INVISIBLE (6225 3650);
FORCEPROP 2 LAST ROOM ST_SATA
J 0
(6175 3600);
DISPLAY 1.361702 (6175 3600);
PAINT ORANGE (6175 3600);
DISPLAY INVISIBLE (6175 3600);
FORCEPROP 1 LASTPIN (6125 3450) $PN 1
J 0
(6115 3465);
DISPLAY 0.787234 (6115 3465);
PAINT ORANGE (6115 3465);
DISPLAY INVISIBLE (6115 3465);
FORCEPROP 1 LASTPIN (6325 3450) $PN 2
J 0
(6310 3465);
DISPLAY 0.787234 (6310 3465);
PAINT ORANGE (6310 3465);
DISPLAY INVISIBLE (6310 3465);
FORCEADD TAP..1
(11950 3725);
FORCEPROP 3 LASTPIN (11900 3725) SIG_NAME SATA6G_TX_DP<0>
J 0
(11910 3735);
DISPLAY 0.659574 (11910 3735);
PAINT MONO (11910 3735);
DISPLAY INVISIBLE (11910 3735);
FORCEPROP 1 LASTPIN (11900 3725) BN 0
J 0
(11888 3733);
DISPLAY 0.617021 (11888 3733);
PAINT GREEN (11888 3733);
FORCEPROP 2 LAST CDS_LIB mstr_standard
J 0
(11950 3725);
PAINT ORANGE (11950 3725);
DISPLAY INVISIBLE (11950 3725);
FORCEPROP 1 LAST BODY_TYPE PLUMBING
J 0
(11950 3775);
DISPLAY 0.872340 (11950 3775);
PAINT GREEN (11950 3775);
DISPLAY INVISIBLE (11950 3775);
FORCEPROP 1 LAST HDL_TAP TRUE
J 0
(12275 3600);
DISPLAY 0.872340 (12275 3600);
PAINT ORANGE (12275 3600);
DISPLAY INVISIBLE (12275 3600);
FORCEPROP 1 LAST PATH I3
J 0
(11948 3725);
DISPLAY 0.872340 (11948 3725);
PAINT GREEN (11948 3725);
DISPLAY INVISIBLE (11948 3725);
FORCEADD CAP_A..2
(6525 3225);
FORCEPROP 1 LAST LOCATION C2L28
J 1
(6525 3325);
DISPLAY 0.617021 (6525 3325);
PAINT AQUA (6525 3325);
FORCEPROP 1 LAST PART_NUMBER A36096-045
J 1
(6525 3275);
DISPLAY 0.617021 (6525 3275);
PAINT BLUE (6525 3275);
FORCEPROP 1 LAST VALUE 0.01UF
J 2
(6525 3125);
DISPLAY 0.617021 (6525 3125);
PAINT SKYBLUE (6525 3125);
FORCEPROP 1 LAST TOLERANCE 10%
J 2
(6525 3075);
DISPLAY 0.617021 (6525 3075);
PAINT SKYBLUE (6525 3075);
FORCEPROP 1 LAST PACK_TYPE 0402V
J 1
(6525 3025);
DISPLAY 0.617021 (6525 3025);
PAINT SKYBLUE (6525 3025);
FORCEPROP 1 LAST VOLTAGE 25V
J 0
(6525 3125);
DISPLAY 0.617021 (6525 3125);
PAINT SKYBLUE (6525 3125);
FORCEPROP 1 LAST MATERIAL X7R
J 0
(6525 3075);
DISPLAY 0.617021 (6525 3075);
PAINT SKYBLUE (6525 3075);
FORCEPROP 2 LAST CDS_LOCATION C2L28
J 1
(6525 3325);
DISPLAY 0.617021 (6525 3325);
PAINT AQUA (6525 3325);
DISPLAY INVISIBLE (6525 3325);
FORCEPROP 2 LAST BOM_COST ST_SATA
J 0
(6475 3325);
DISPLAY 1.361702 (6475 3325);
PAINT ORANGE (6475 3325);
DISPLAY INVISIBLE (6475 3325);
FORCEPROP 2 LAST CDS_LIB dev_discrete
J 0
(6525 3225);
PAINT ORANGE (6525 3225);
DISPLAY INVISIBLE (6525 3225);
FORCEPROP 2 LAST CDS_SEC 1
J 0
(6525 3475);
DISPLAY 1.021277 (6525 3475);
PAINT ORANGE (6525 3475);
DISPLAY INVISIBLE (6525 3475);
FORCEPROP 2 LAST $SEC 1
J 0
(6525 3475);
DISPLAY 0.680851 (6525 3475);
PAINT MONO (6525 3475);
DISPLAY INVISIBLE (6525 3475);
FORCEPROP 1 LAST PATH I30
J 0
(6525 3425);
DISPLAY 0.978723 (6525 3425);
PAINT WHITE (6525 3425);
DISPLAY INVISIBLE (6525 3425);
FORCEPROP 2 LAST ROOM ST_SATA
J 0
(6475 3375);
DISPLAY 1.361702 (6475 3375);
PAINT ORANGE (6475 3375);
DISPLAY INVISIBLE (6475 3375);
FORCEPROP 1 LASTPIN (6425 3225) $PN 1
J 0
(6415 3240);
DISPLAY 0.787234 (6415 3240);
PAINT ORANGE (6415 3240);
DISPLAY INVISIBLE (6415 3240);
FORCEPROP 1 LASTPIN (6625 3225) $PN 2
J 0
(6610 3240);
DISPLAY 0.787234 (6610 3240);
PAINT ORANGE (6610 3240);
DISPLAY INVISIBLE (6610 3240);
FORCEADD CAP_A..2
(6600 2475);
FORCEPROP 1 LAST LOCATION C2L35
J 1
(6600 2575);
DISPLAY 0.617021 (6600 2575);
PAINT AQUA (6600 2575);
FORCEPROP 1 LAST PART_NUMBER A36096-045
J 1
(6600 2525);
DISPLAY 0.617021 (6600 2525);
PAINT BLUE (6600 2525);
FORCEPROP 1 LAST VALUE 0.01UF
J 2
(6600 2375);
DISPLAY 0.617021 (6600 2375);
PAINT SKYBLUE (6600 2375);
FORCEPROP 1 LAST TOLERANCE 10%
J 2
(6600 2325);
DISPLAY 0.617021 (6600 2325);
PAINT SKYBLUE (6600 2325);
FORCEPROP 1 LAST PACK_TYPE 0402V
J 1
(6600 2275);
DISPLAY 0.617021 (6600 2275);
PAINT SKYBLUE (6600 2275);
FORCEPROP 1 LAST VOLTAGE 25V
J 0
(6600 2375);
DISPLAY 0.617021 (6600 2375);
PAINT SKYBLUE (6600 2375);
FORCEPROP 1 LAST MATERIAL X7R
J 0
(6600 2325);
DISPLAY 0.617021 (6600 2325);
PAINT SKYBLUE (6600 2325);
FORCEPROP 2 LAST CDS_LOCATION C2L35
J 1
(6600 2575);
DISPLAY 0.617021 (6600 2575);
PAINT AQUA (6600 2575);
DISPLAY INVISIBLE (6600 2575);
FORCEPROP 2 LAST BOM_COST ST_SATA
J 0
(6550 2575);
DISPLAY 1.361702 (6550 2575);
PAINT ORANGE (6550 2575);
DISPLAY INVISIBLE (6550 2575);
FORCEPROP 2 LAST CDS_LIB dev_discrete
J 0
(6600 2475);
PAINT ORANGE (6600 2475);
DISPLAY INVISIBLE (6600 2475);
FORCEPROP 2 LAST CDS_SEC 1
J 0
(6600 2725);
DISPLAY 1.021277 (6600 2725);
PAINT ORANGE (6600 2725);
DISPLAY INVISIBLE (6600 2725);
FORCEPROP 2 LAST $SEC 1
J 0
(6600 2725);
DISPLAY 0.680851 (6600 2725);
PAINT MONO (6600 2725);
DISPLAY INVISIBLE (6600 2725);
FORCEPROP 1 LAST PATH I31
J 0
(6600 2675);
DISPLAY 0.978723 (6600 2675);
PAINT WHITE (6600 2675);
DISPLAY INVISIBLE (6600 2675);
FORCEPROP 2 LAST ROOM ST_SATA
J 0
(6550 2625);
DISPLAY 1.361702 (6550 2625);
PAINT ORANGE (6550 2625);
DISPLAY INVISIBLE (6550 2625);
FORCEPROP 1 LASTPIN (6500 2475) $PN 1
J 0
(6490 2490);
DISPLAY 0.787234 (6490 2490);
PAINT ORANGE (6490 2490);
DISPLAY INVISIBLE (6490 2490);
FORCEPROP 1 LASTPIN (6700 2475) $PN 2
J 0
(6685 2490);
DISPLAY 0.787234 (6685 2490);
PAINT ORANGE (6685 2490);
DISPLAY INVISIBLE (6685 2490);
FORCEADD CAP_A..2
(6225 3025);
FORCEPROP 1 LAST LOCATION C2L29
J 1
(6225 3125);
DISPLAY 0.617021 (6225 3125);
PAINT AQUA (6225 3125);
FORCEPROP 1 LAST PART_NUMBER A36096-045
J 1
(6225 3075);
DISPLAY 0.617021 (6225 3075);
PAINT BLUE (6225 3075);
FORCEPROP 1 LAST VALUE 0.01UF
J 2
(6225 2925);
DISPLAY 0.617021 (6225 2925);
PAINT SKYBLUE (6225 2925);
FORCEPROP 1 LAST TOLERANCE 10%
J 2
(6225 2875);
DISPLAY 0.617021 (6225 2875);
PAINT SKYBLUE (6225 2875);
FORCEPROP 1 LAST PACK_TYPE 0402V
J 1
(6225 2825);
DISPLAY 0.617021 (6225 2825);
PAINT SKYBLUE (6225 2825);
FORCEPROP 1 LAST VOLTAGE 25V
J 0
(6225 2925);
DISPLAY 0.617021 (6225 2925);
PAINT SKYBLUE (6225 2925);
FORCEPROP 1 LAST MATERIAL X7R
J 0
(6225 2875);
DISPLAY 0.617021 (6225 2875);
PAINT SKYBLUE (6225 2875);
FORCEPROP 2 LAST CDS_LOCATION C2L29
J 1
(6225 3125);
DISPLAY 0.617021 (6225 3125);
PAINT AQUA (6225 3125);
DISPLAY INVISIBLE (6225 3125);
FORCEPROP 2 LAST BOM_COST ST_SATA
J 0
(6175 3125);
DISPLAY 1.361702 (6175 3125);
PAINT ORANGE (6175 3125);
DISPLAY INVISIBLE (6175 3125);
FORCEPROP 2 LAST CDS_LIB dev_discrete
J 0
(6225 3025);
PAINT ORANGE (6225 3025);
DISPLAY INVISIBLE (6225 3025);
FORCEPROP 2 LAST CDS_SEC 1
J 0
(6225 3275);
DISPLAY 1.021277 (6225 3275);
PAINT ORANGE (6225 3275);
DISPLAY INVISIBLE (6225 3275);
FORCEPROP 2 LAST $SEC 1
J 0
(6225 3275);
DISPLAY 0.680851 (6225 3275);
PAINT MONO (6225 3275);
DISPLAY INVISIBLE (6225 3275);
FORCEPROP 1 LAST PATH I32
J 0
(6225 3225);
DISPLAY 0.978723 (6225 3225);
PAINT WHITE (6225 3225);
DISPLAY INVISIBLE (6225 3225);
FORCEPROP 2 LAST ROOM ST_SATA
J 0
(6175 3175);
DISPLAY 1.361702 (6175 3175);
PAINT ORANGE (6175 3175);
DISPLAY INVISIBLE (6175 3175);
FORCEPROP 1 LASTPIN (6125 3025) $PN 1
J 0
(6115 3040);
DISPLAY 0.787234 (6115 3040);
PAINT ORANGE (6115 3040);
DISPLAY INVISIBLE (6115 3040);
FORCEPROP 1 LASTPIN (6325 3025) $PN 2
J 0
(6310 3040);
DISPLAY 0.787234 (6310 3040);
PAINT ORANGE (6310 3040);
DISPLAY INVISIBLE (6310 3040);
FORCEADD TAP..6
(5450 3675);
FORCEPROP 3 LASTPIN (5500 3675) SIG_NAME SATA6G_RX_DP<0>
J 0
(5510 3685);
DISPLAY 0.659574 (5510 3685);
PAINT MONO (5510 3685);
DISPLAY INVISIBLE (5510 3685);
FORCEPROP 1 LASTPIN (5500 3675) BN 0
J 0
(5448 3683);
DISPLAY 0.617021 (5448 3683);
PAINT GREEN (5448 3683);
FORCEPROP 2 LAST CDS_LIB mstr_standard
J 0
(5450 3675);
PAINT ORANGE (5450 3675);
DISPLAY INVISIBLE (5450 3675);
FORCEPROP 1 LAST BODY_TYPE PLUMBING
J 0
(5450 3625);
DISPLAY 0.872340 (5450 3625);
PAINT GREEN (5450 3625);
DISPLAY INVISIBLE (5450 3625);
FORCEPROP 1 LAST HDL_TAP TRUE
J 0
(5775 3550);
DISPLAY 0.872340 (5775 3550);
PAINT ORANGE (5775 3550);
DISPLAY INVISIBLE (5775 3550);
FORCEPROP 1 LAST PATH I33
J 0
(5448 3675);
DISPLAY 0.872340 (5448 3675);
PAINT GREEN (5448 3675);
DISPLAY INVISIBLE (5448 3675);
FORCEADD TAP..6
(5600 3450);
FORCEPROP 3 LASTPIN (5650 3450) SIG_NAME SATA6G_RX_DN<0>
J 0
(5660 3460);
DISPLAY 0.659574 (5660 3460);
PAINT MONO (5660 3460);
DISPLAY INVISIBLE (5660 3460);
FORCEPROP 1 LASTPIN (5650 3450) BN 0
J 0
(5598 3458);
DISPLAY 0.617021 (5598 3458);
PAINT GREEN (5598 3458);
FORCEPROP 2 LAST CDS_LIB mstr_standard
J 0
(5600 3450);
PAINT ORANGE (5600 3450);
DISPLAY INVISIBLE (5600 3450);
FORCEPROP 1 LAST BODY_TYPE PLUMBING
J 0
(5600 3400);
DISPLAY 0.872340 (5600 3400);
PAINT GREEN (5600 3400);
DISPLAY INVISIBLE (5600 3400);
FORCEPROP 1 LAST HDL_TAP TRUE
J 0
(5925 3325);
DISPLAY 0.872340 (5925 3325);
PAINT ORANGE (5925 3325);
DISPLAY INVISIBLE (5925 3325);
FORCEPROP 1 LAST PATH I34
J 0
(5598 3450);
DISPLAY 0.872340 (5598 3450);
PAINT GREEN (5598 3450);
DISPLAY INVISIBLE (5598 3450);
FORCEADD TAP..6
(5600 3025);
FORCEPROP 3 LASTPIN (5650 3025) SIG_NAME SATA6G_RX_DN<1>
J 0
(5660 3035);
DISPLAY 0.659574 (5660 3035);
PAINT MONO (5660 3035);
DISPLAY INVISIBLE (5660 3035);
FORCEPROP 1 LASTPIN (5650 3025) BN 1
J 0
(5598 3033);
DISPLAY 0.617021 (5598 3033);
PAINT GREEN (5598 3033);
FORCEPROP 2 LAST CDS_LIB mstr_standard
J 0
(5600 3025);
PAINT ORANGE (5600 3025);
DISPLAY INVISIBLE (5600 3025);
FORCEPROP 1 LAST BODY_TYPE PLUMBING
J 0
(5600 2975);
DISPLAY 0.872340 (5600 2975);
PAINT GREEN (5600 2975);
DISPLAY INVISIBLE (5600 2975);
FORCEPROP 1 LAST HDL_TAP TRUE
J 0
(5925 2900);
DISPLAY 0.872340 (5925 2900);
PAINT ORANGE (5925 2900);
DISPLAY INVISIBLE (5925 2900);
FORCEPROP 1 LAST PATH I35
J 0
(5598 3025);
DISPLAY 0.872340 (5598 3025);
PAINT GREEN (5598 3025);
DISPLAY INVISIBLE (5598 3025);
FORCEADD TAP..6
(5450 3225);
FORCEPROP 3 LASTPIN (5500 3225) SIG_NAME SATA6G_RX_DP<1>
J 0
(5510 3235);
DISPLAY 0.659574 (5510 3235);
PAINT MONO (5510 3235);
DISPLAY INVISIBLE (5510 3235);
FORCEPROP 1 LASTPIN (5500 3225) BN 1
J 0
(5448 3233);
DISPLAY 0.617021 (5448 3233);
PAINT GREEN (5448 3233);
FORCEPROP 2 LAST CDS_LIB mstr_standard
J 0
(5450 3225);
PAINT ORANGE (5450 3225);
DISPLAY INVISIBLE (5450 3225);
FORCEPROP 1 LAST BODY_TYPE PLUMBING
J 0
(5450 3175);
DISPLAY 0.872340 (5450 3175);
PAINT GREEN (5450 3175);
DISPLAY INVISIBLE (5450 3175);
FORCEPROP 1 LAST HDL_TAP TRUE
J 0
(5775 3100);
DISPLAY 0.872340 (5775 3100);
PAINT ORANGE (5775 3100);
DISPLAY INVISIBLE (5775 3100);
FORCEPROP 1 LAST PATH I36
J 0
(5448 3225);
DISPLAY 0.872340 (5448 3225);
PAINT GREEN (5448 3225);
DISPLAY INVISIBLE (5448 3225);
FORCEADD TAP..6
(5600 2250);
FORCEPROP 3 LASTPIN (5650 2250) SIG_NAME SATA6G_RX_DN<2>
J 0
(5660 2260);
DISPLAY 0.659574 (5660 2260);
PAINT MONO (5660 2260);
DISPLAY INVISIBLE (5660 2260);
FORCEPROP 1 LASTPIN (5650 2250) BN 2
J 0
(5598 2258);
DISPLAY 0.617021 (5598 2258);
PAINT GREEN (5598 2258);
FORCEPROP 2 LAST CDS_LIB mstr_standard
J 0
(5600 2250);
PAINT ORANGE (5600 2250);
DISPLAY INVISIBLE (5600 2250);
FORCEPROP 1 LAST BODY_TYPE PLUMBING
J 0
(5600 2200);
DISPLAY 0.872340 (5600 2200);
PAINT GREEN (5600 2200);
DISPLAY INVISIBLE (5600 2200);
FORCEPROP 1 LAST HDL_TAP TRUE
J 0
(5925 2125);
DISPLAY 0.872340 (5925 2125);
PAINT ORANGE (5925 2125);
DISPLAY INVISIBLE (5925 2125);
FORCEPROP 1 LAST PATH I37
J 0
(5598 2250);
DISPLAY 0.872340 (5598 2250);
PAINT GREEN (5598 2250);
DISPLAY INVISIBLE (5598 2250);
FORCEADD TAP..6
(5450 2475);
FORCEPROP 3 LASTPIN (5500 2475) SIG_NAME SATA6G_RX_DP<2>
J 0
(5510 2485);
DISPLAY 0.659574 (5510 2485);
PAINT MONO (5510 2485);
DISPLAY INVISIBLE (5510 2485);
FORCEPROP 1 LASTPIN (5500 2475) BN 2
J 0
(5448 2483);
DISPLAY 0.617021 (5448 2483);
PAINT GREEN (5448 2483);
FORCEPROP 2 LAST CDS_LIB mstr_standard
J 0
(5450 2475);
PAINT ORANGE (5450 2475);
DISPLAY INVISIBLE (5450 2475);
FORCEPROP 1 LAST BODY_TYPE PLUMBING
J 0
(5450 2425);
DISPLAY 0.872340 (5450 2425);
PAINT GREEN (5450 2425);
DISPLAY INVISIBLE (5450 2425);
FORCEPROP 1 LAST HDL_TAP TRUE
J 0
(5775 2350);
DISPLAY 0.872340 (5775 2350);
PAINT ORANGE (5775 2350);
DISPLAY INVISIBLE (5775 2350);
FORCEPROP 1 LAST PATH I38
J 0
(5448 2475);
DISPLAY 0.872340 (5448 2475);
PAINT GREEN (5448 2475);
DISPLAY INVISIBLE (5448 2475);
FORCEADD CAP_A..2
(6300 2250);
FORCEPROP 1 LAST LOCATION C2L36
J 1
(6300 2350);
DISPLAY 0.617021 (6300 2350);
PAINT AQUA (6300 2350);
FORCEPROP 1 LAST PART_NUMBER A36096-045
J 1
(6300 2300);
DISPLAY 0.617021 (6300 2300);
PAINT BLUE (6300 2300);
FORCEPROP 1 LAST VALUE 0.01UF
J 2
(6300 2150);
DISPLAY 0.617021 (6300 2150);
PAINT SKYBLUE (6300 2150);
FORCEPROP 1 LAST TOLERANCE 10%
J 2
(6300 2100);
DISPLAY 0.617021 (6300 2100);
PAINT SKYBLUE (6300 2100);
FORCEPROP 1 LAST PACK_TYPE 0402V
J 1
(6300 2050);
DISPLAY 0.617021 (6300 2050);
PAINT SKYBLUE (6300 2050);
FORCEPROP 1 LAST VOLTAGE 25V
J 0
(6300 2150);
DISPLAY 0.617021 (6300 2150);
PAINT SKYBLUE (6300 2150);
FORCEPROP 1 LAST MATERIAL X7R
J 0
(6300 2100);
DISPLAY 0.617021 (6300 2100);
PAINT SKYBLUE (6300 2100);
FORCEPROP 2 LAST CDS_LOCATION C2L36
J 1
(6300 2350);
DISPLAY 0.617021 (6300 2350);
PAINT AQUA (6300 2350);
DISPLAY INVISIBLE (6300 2350);
FORCEPROP 2 LAST BOM_COST ST_SATA
J 0
(6250 2350);
DISPLAY 1.361702 (6250 2350);
PAINT ORANGE (6250 2350);
DISPLAY INVISIBLE (6250 2350);
FORCEPROP 2 LAST CDS_LIB dev_discrete
J 0
(6300 2250);
PAINT ORANGE (6300 2250);
DISPLAY INVISIBLE (6300 2250);
FORCEPROP 2 LAST CDS_SEC 1
J 0
(6300 2500);
DISPLAY 1.021277 (6300 2500);
PAINT ORANGE (6300 2500);
DISPLAY INVISIBLE (6300 2500);
FORCEPROP 2 LAST $SEC 1
J 0
(6300 2500);
DISPLAY 0.680851 (6300 2500);
PAINT MONO (6300 2500);
DISPLAY INVISIBLE (6300 2500);
FORCEPROP 1 LAST PATH I39
J 0
(6300 2450);
DISPLAY 0.978723 (6300 2450);
PAINT WHITE (6300 2450);
DISPLAY INVISIBLE (6300 2450);
FORCEPROP 2 LAST ROOM ST_SATA
J 0
(6250 2400);
DISPLAY 1.361702 (6250 2400);
PAINT ORANGE (6250 2400);
DISPLAY INVISIBLE (6250 2400);
FORCEPROP 1 LASTPIN (6200 2250) $PN 1
J 0
(6190 2265);
DISPLAY 0.787234 (6190 2265);
PAINT ORANGE (6190 2265);
DISPLAY INVISIBLE (6190 2265);
FORCEPROP 1 LASTPIN (6400 2250) $PN 2
J 0
(6385 2265);
DISPLAY 0.787234 (6385 2265);
PAINT ORANGE (6385 2265);
DISPLAY INVISIBLE (6385 2265);
FORCEADD TAP..1
(11950 3250);
FORCEPROP 3 LASTPIN (11900 3250) SIG_NAME SATA6G_TX_DP<1>
J 0
(11910 3260);
DISPLAY 0.659574 (11910 3260);
PAINT MONO (11910 3260);
DISPLAY INVISIBLE (11910 3260);
FORCEPROP 1 LASTPIN (11900 3250) BN 1
J 0
(11888 3258);
DISPLAY 0.617021 (11888 3258);
PAINT GREEN (11888 3258);
FORCEPROP 2 LAST CDS_LIB mstr_standard
J 0
(11950 3250);
PAINT ORANGE (11950 3250);
DISPLAY INVISIBLE (11950 3250);
FORCEPROP 1 LAST BODY_TYPE PLUMBING
J 0
(11950 3300);
DISPLAY 0.872340 (11950 3300);
PAINT GREEN (11950 3300);
DISPLAY INVISIBLE (11950 3300);
FORCEPROP 1 LAST HDL_TAP TRUE
J 0
(12275 3125);
DISPLAY 0.872340 (12275 3125);
PAINT ORANGE (12275 3125);
DISPLAY INVISIBLE (12275 3125);
FORCEPROP 1 LAST PATH I4
J 0
(11948 3250);
DISPLAY 0.872340 (11948 3250);
PAINT GREEN (11948 3250);
DISPLAY INVISIBLE (11948 3250);
FORCEADD CAP_A..2
(6600 2025);
FORCEPROP 1 LAST LOCATION C2L33
J 1
(6600 2125);
DISPLAY 0.617021 (6600 2125);
PAINT AQUA (6600 2125);
FORCEPROP 1 LAST PART_NUMBER A36096-045
J 1
(6600 2075);
DISPLAY 0.617021 (6600 2075);
PAINT BLUE (6600 2075);
FORCEPROP 1 LAST VALUE 0.01UF
J 2
(6600 1925);
DISPLAY 0.617021 (6600 1925);
PAINT SKYBLUE (6600 1925);
FORCEPROP 1 LAST TOLERANCE 10%
J 2
(6600 1875);
DISPLAY 0.617021 (6600 1875);
PAINT SKYBLUE (6600 1875);
FORCEPROP 1 LAST PACK_TYPE 0402V
J 1
(6600 1825);
DISPLAY 0.617021 (6600 1825);
PAINT SKYBLUE (6600 1825);
FORCEPROP 1 LAST VOLTAGE 25V
J 0
(6600 1925);
DISPLAY 0.617021 (6600 1925);
PAINT SKYBLUE (6600 1925);
FORCEPROP 1 LAST MATERIAL X7R
J 0
(6600 1875);
DISPLAY 0.617021 (6600 1875);
PAINT SKYBLUE (6600 1875);
FORCEPROP 2 LAST CDS_LOCATION C2L33
J 1
(6600 2125);
DISPLAY 0.617021 (6600 2125);
PAINT AQUA (6600 2125);
DISPLAY INVISIBLE (6600 2125);
FORCEPROP 2 LAST BOM_COST ST_SATA
J 0
(6550 2125);
DISPLAY 1.361702 (6550 2125);
PAINT ORANGE (6550 2125);
DISPLAY INVISIBLE (6550 2125);
FORCEPROP 2 LAST CDS_LIB dev_discrete
J 0
(6600 2025);
PAINT ORANGE (6600 2025);
DISPLAY INVISIBLE (6600 2025);
FORCEPROP 2 LAST CDS_SEC 1
J 0
(6600 2275);
DISPLAY 1.021277 (6600 2275);
PAINT ORANGE (6600 2275);
DISPLAY INVISIBLE (6600 2275);
FORCEPROP 2 LAST $SEC 1
J 0
(6600 2275);
DISPLAY 0.680851 (6600 2275);
PAINT MONO (6600 2275);
DISPLAY INVISIBLE (6600 2275);
FORCEPROP 1 LAST PATH I40
J 0
(6600 2225);
DISPLAY 0.978723 (6600 2225);
PAINT WHITE (6600 2225);
DISPLAY INVISIBLE (6600 2225);
FORCEPROP 2 LAST ROOM ST_SATA
J 0
(6550 2175);
DISPLAY 1.361702 (6550 2175);
PAINT ORANGE (6550 2175);
DISPLAY INVISIBLE (6550 2175);
FORCEPROP 1 LASTPIN (6500 2025) $PN 1
J 0
(6490 2040);
DISPLAY 0.787234 (6490 2040);
PAINT ORANGE (6490 2040);
DISPLAY INVISIBLE (6490 2040);
FORCEPROP 1 LASTPIN (6700 2025) $PN 2
J 0
(6685 2040);
DISPLAY 0.787234 (6685 2040);
PAINT ORANGE (6685 2040);
DISPLAY INVISIBLE (6685 2040);
FORCEADD CAP_A..2
(6300 1825);
FORCEPROP 1 LAST LOCATION C2L34
J 1
(6300 1925);
DISPLAY 0.617021 (6300 1925);
PAINT AQUA (6300 1925);
FORCEPROP 1 LAST PART_NUMBER A36096-045
J 1
(6300 1875);
DISPLAY 0.617021 (6300 1875);
PAINT BLUE (6300 1875);
FORCEPROP 1 LAST VALUE 0.01UF
J 2
(6300 1725);
DISPLAY 0.617021 (6300 1725);
PAINT SKYBLUE (6300 1725);
FORCEPROP 1 LAST TOLERANCE 10%
J 2
(6300 1675);
DISPLAY 0.617021 (6300 1675);
PAINT SKYBLUE (6300 1675);
FORCEPROP 1 LAST PACK_TYPE 0402V
J 1
(6300 1625);
DISPLAY 0.617021 (6300 1625);
PAINT SKYBLUE (6300 1625);
FORCEPROP 1 LAST VOLTAGE 25V
J 0
(6300 1725);
DISPLAY 0.617021 (6300 1725);
PAINT SKYBLUE (6300 1725);
FORCEPROP 1 LAST MATERIAL X7R
J 0
(6300 1675);
DISPLAY 0.617021 (6300 1675);
PAINT SKYBLUE (6300 1675);
FORCEPROP 2 LAST CDS_LOCATION C2L34
J 1
(6300 1925);
DISPLAY 0.617021 (6300 1925);
PAINT AQUA (6300 1925);
DISPLAY INVISIBLE (6300 1925);
FORCEPROP 2 LAST BOM_COST ST_SATA
J 0
(6250 1925);
DISPLAY 1.361702 (6250 1925);
PAINT ORANGE (6250 1925);
DISPLAY INVISIBLE (6250 1925);
FORCEPROP 2 LAST CDS_LIB dev_discrete
J 0
(6300 1825);
PAINT ORANGE (6300 1825);
DISPLAY INVISIBLE (6300 1825);
FORCEPROP 2 LAST CDS_SEC 1
J 0
(6300 2075);
DISPLAY 1.021277 (6300 2075);
PAINT ORANGE (6300 2075);
DISPLAY INVISIBLE (6300 2075);
FORCEPROP 2 LAST $SEC 1
J 0
(6300 2075);
DISPLAY 0.680851 (6300 2075);
PAINT MONO (6300 2075);
DISPLAY INVISIBLE (6300 2075);
FORCEPROP 1 LAST PATH I41
J 0
(6300 2025);
DISPLAY 0.978723 (6300 2025);
PAINT WHITE (6300 2025);
DISPLAY INVISIBLE (6300 2025);
FORCEPROP 2 LAST ROOM ST_SATA
J 0
(6250 1975);
DISPLAY 1.361702 (6250 1975);
PAINT ORANGE (6250 1975);
DISPLAY INVISIBLE (6250 1975);
FORCEPROP 1 LASTPIN (6200 1825) $PN 1
J 0
(6190 1840);
DISPLAY 0.787234 (6190 1840);
PAINT ORANGE (6190 1840);
DISPLAY INVISIBLE (6190 1840);
FORCEPROP 1 LASTPIN (6400 1825) $PN 2
J 0
(6385 1840);
DISPLAY 0.787234 (6385 1840);
PAINT ORANGE (6385 1840);
DISPLAY INVISIBLE (6385 1840);
FORCEADD TAP..6
(5450 2025);
FORCEPROP 3 LASTPIN (5500 2025) SIG_NAME SATA6G_RX_DP<3>
J 0
(5510 2035);
DISPLAY 0.659574 (5510 2035);
PAINT MONO (5510 2035);
DISPLAY INVISIBLE (5510 2035);
FORCEPROP 1 LASTPIN (5500 2025) BN 3
J 0
(5448 2033);
DISPLAY 0.617021 (5448 2033);
PAINT GREEN (5448 2033);
FORCEPROP 2 LAST CDS_LIB mstr_standard
J 0
(5450 2025);
PAINT ORANGE (5450 2025);
DISPLAY INVISIBLE (5450 2025);
FORCEPROP 1 LAST BODY_TYPE PLUMBING
J 0
(5450 1975);
DISPLAY 0.872340 (5450 1975);
PAINT GREEN (5450 1975);
DISPLAY INVISIBLE (5450 1975);
FORCEPROP 1 LAST HDL_TAP TRUE
J 0
(5775 1900);
DISPLAY 0.872340 (5775 1900);
PAINT ORANGE (5775 1900);
DISPLAY INVISIBLE (5775 1900);
FORCEPROP 1 LAST PATH I42
J 0
(5448 2025);
DISPLAY 0.872340 (5448 2025);
PAINT GREEN (5448 2025);
DISPLAY INVISIBLE (5448 2025);
FORCEADD TAP..6
(5600 1825);
FORCEPROP 3 LASTPIN (5650 1825) SIG_NAME SATA6G_RX_DN<3>
J 0
(5660 1835);
DISPLAY 0.659574 (5660 1835);
PAINT MONO (5660 1835);
DISPLAY INVISIBLE (5660 1835);
FORCEPROP 1 LASTPIN (5650 1825) BN 3
J 0
(5598 1833);
DISPLAY 0.617021 (5598 1833);
PAINT GREEN (5598 1833);
FORCEPROP 2 LAST CDS_LIB mstr_standard
J 0
(5600 1825);
PAINT ORANGE (5600 1825);
DISPLAY INVISIBLE (5600 1825);
FORCEPROP 1 LAST BODY_TYPE PLUMBING
J 0
(5600 1775);
DISPLAY 0.872340 (5600 1775);
PAINT GREEN (5600 1775);
DISPLAY INVISIBLE (5600 1775);
FORCEPROP 1 LAST HDL_TAP TRUE
J 0
(5925 1700);
DISPLAY 0.872340 (5925 1700);
PAINT ORANGE (5925 1700);
DISPLAY INVISIBLE (5925 1700);
FORCEPROP 1 LAST PATH I43
J 0
(5598 1825);
DISPLAY 0.872340 (5598 1825);
PAINT GREEN (5598 1825);
DISPLAY INVISIBLE (5598 1825);
FORCEADD OFFPAGE..1
(7075 2725);
FORCEPROP 2 LAST $XR0 178 
J 0
(6823 2725);
DISPLAY 0.638298 (6823 2725);
PAINT MONO (6823 2725);
FORCEPROP 2 LAST CDS_LIB mstr_standard
J 0
(7075 2725);
PAINT MONO (7075 2725);
DISPLAY INVISIBLE (7075 2725);
FORCEPROP 1 LAST OFFPAGE TRUE
J 0
(7400 2600);
DISPLAY 0.872340 (7400 2600);
PAINT GREEN (7400 2600);
DISPLAY INVISIBLE (7400 2600);
FORCEPROP 1 LAST COMMENT_BODY TRUE
J 0
(7200 2625);
DISPLAY 0.872340 (7200 2625);
PAINT GREEN (7200 2625);
DISPLAY INVISIBLE (7200 2625);
FORCEPROP 2 LAST PATH I44
J 0
(7125 2800);
DISPLAY 1.021277 (7125 2800);
PAINT ORANGE (7125 2800);
DISPLAY INVISIBLE (7125 2800);
FORCEADD OFFPAGE..4
(10125 2825);
FORCEPROP 2 LAST $XR0 178 
J 0
(10311 2825);
DISPLAY 0.638298 (10311 2825);
PAINT MONO (10311 2825);
FORCEPROP 2 LAST CDS_LIB mstr_standard
J 0
(10125 2825);
PAINT MONO (10125 2825);
DISPLAY INVISIBLE (10125 2825);
FORCEPROP 1 LAST OFFPAGE TRUE
J 0
(10450 2700);
DISPLAY 0.872340 (10450 2700);
PAINT GREEN (10450 2700);
DISPLAY INVISIBLE (10450 2700);
FORCEPROP 1 LAST COMMENT_BODY TRUE
J 0
(10100 2725);
DISPLAY 0.872340 (10100 2725);
PAINT GREEN (10100 2725);
DISPLAY INVISIBLE (10100 2725);
FORCEPROP 2 LAST PATH I45
J 0
(10300 2900);
DISPLAY 1.021277 (10300 2900);
PAINT ORANGE (10300 2900);
DISPLAY INVISIBLE (10300 2900);
FORCEADD OFFPAGE..4
(10125 2775);
FORCEPROP 2 LAST $XR0 178 
J 0
(10311 2775);
DISPLAY 0.638298 (10311 2775);
PAINT MONO (10311 2775);
FORCEPROP 2 LAST CDS_LIB mstr_standard
J 0
(10125 2775);
PAINT MONO (10125 2775);
DISPLAY INVISIBLE (10125 2775);
FORCEPROP 1 LAST OFFPAGE TRUE
J 0
(10450 2650);
DISPLAY 0.872340 (10450 2650);
PAINT GREEN (10450 2650);
DISPLAY INVISIBLE (10450 2650);
FORCEPROP 1 LAST COMMENT_BODY TRUE
J 0
(10100 2675);
DISPLAY 0.872340 (10100 2675);
PAINT GREEN (10100 2675);
DISPLAY INVISIBLE (10100 2675);
FORCEPROP 2 LAST PATH I46
J 0
(10300 2850);
DISPLAY 1.021277 (10300 2850);
PAINT ORANGE (10300 2850);
DISPLAY INVISIBLE (10300 2850);
FORCEADD RES..2
(12250 2425);
FORCEPROP 1 LAST LOCATION R1L3
J 0
(12295 2550);
DISPLAY 0.617021 (12295 2550);
PAINT AQUA (12295 2550);
FORCEPROP 1 LAST PART_NUMBER G21796-026
J 0
(12290 2300);
DISPLAY 0.617021 (12290 2300);
PAINT BLUE (12290 2300);
FORCEPROP 1 LAST VALUE 1.00K
J 0
(12295 2500);
DISPLAY 0.617021 (12295 2500);
PAINT SKYBLUE (12295 2500);
FORCEPROP 1 LAST TOLERANCE 1%
J 0
(12295 2450);
DISPLAY 0.617021 (12295 2450);
PAINT SKYBLUE (12295 2450);
FORCEPROP 1 LAST PACK_TYPE 0402
J 0
(12290 2250);
DISPLAY 0.617021 (12290 2250);
PAINT SKYBLUE (12290 2250);
FORCEPROP 1 LAST MATERIAL CHIP
J 0
(12290 2350);
DISPLAY 0.617021 (12290 2350);
PAINT SKYBLUE (12290 2350);
FORCEPROP 1 LAST WATTAGE 1/16W
J 0
(12290 2400);
DISPLAY 0.617021 (12290 2400);
PAINT SKYBLUE (12290 2400);
FORCEPROP 2 LAST CDS_LIB mstr_discrete
J 0
(12250 2425);
PAINT ORANGE (12250 2425);
DISPLAY INVISIBLE (12250 2425);
FORCEPROP 2 LAST BOM_COST ST_SATA
J 0
(12300 2600);
DISPLAY 1.361702 (12300 2600);
PAINT ORANGE (12300 2600);
DISPLAY INVISIBLE (12300 2600);
FORCEPROP 2 LAST CDS_SEC 1
J 0
(12300 2650);
DISPLAY 1.021277 (12300 2650);
PAINT ORANGE (12300 2650);
DISPLAY INVISIBLE (12300 2650);
FORCEPROP 2 LAST $SEC 1
J 0
(12300 2650);
DISPLAY 0.680851 (12300 2650);
PAINT MONO (12300 2650);
DISPLAY INVISIBLE (12300 2650);
FORCEPROP 2 LAST CDS_LOCATION R1L3
J 0
(12295 2550);
DISPLAY 0.617021 (12295 2550);
PAINT AQUA (12295 2550);
DISPLAY INVISIBLE (12295 2550);
FORCEPROP 1 LAST PATH I5
J 0
(12300 2600);
DISPLAY 0.978723 (12300 2600);
PAINT WHITE (12300 2600);
DISPLAY INVISIBLE (12300 2600);
FORCEPROP 2 LAST ROOM ST_SATA
J 0
(12300 2600);
DISPLAY 1.361702 (12300 2600);
PAINT ORANGE (12300 2600);
DISPLAY INVISIBLE (12300 2600);
FORCEPROP 1 LASTPIN (12250 2325) $PN 2
J 0
(12255 2335);
DISPLAY 0.787234 (12255 2335);
PAINT ORANGE (12255 2335);
DISPLAY INVISIBLE (12255 2335);
FORCEPROP 1 LASTPIN (12250 2525) $PN 1
J 0
(12255 2487);
DISPLAY 0.787234 (12255 2487);
PAINT ORANGE (12255 2487);
DISPLAY INVISIBLE (12255 2487);
FORCEADD TAP..1
(11950 2475);
FORCEPROP 3 LASTPIN (11900 2475) SIG_NAME SATA6G_TX_DP<2>
J 0
(11910 2485);
DISPLAY 0.659574 (11910 2485);
PAINT MONO (11910 2485);
DISPLAY INVISIBLE (11910 2485);
FORCEPROP 1 LASTPIN (11900 2475) BN 2
J 0
(11888 2483);
DISPLAY 0.617021 (11888 2483);
PAINT GREEN (11888 2483);
FORCEPROP 2 LAST CDS_LIB mstr_standard
J 0
(11950 2475);
PAINT ORANGE (11950 2475);
DISPLAY INVISIBLE (11950 2475);
FORCEPROP 1 LAST BODY_TYPE PLUMBING
J 0
(11950 2525);
DISPLAY 0.872340 (11950 2525);
PAINT GREEN (11950 2525);
DISPLAY INVISIBLE (11950 2525);
FORCEPROP 1 LAST HDL_TAP TRUE
J 0
(12275 2350);
DISPLAY 0.872340 (12275 2350);
PAINT ORANGE (12275 2350);
DISPLAY INVISIBLE (12275 2350);
FORCEPROP 1 LAST PATH I6
J 0
(11948 2475);
DISPLAY 0.872340 (11948 2475);
PAINT GREEN (11948 2475);
DISPLAY INVISIBLE (11948 2475);
FORCEADD TAP..1
(11800 3475);
FORCEPROP 3 LASTPIN (11750 3475) SIG_NAME SATA6G_TX_DN<0>
J 0
(11760 3485);
DISPLAY 0.659574 (11760 3485);
PAINT MONO (11760 3485);
DISPLAY INVISIBLE (11760 3485);
FORCEPROP 1 LASTPIN (11750 3475) BN 0
J 0
(11738 3483);
DISPLAY 0.617021 (11738 3483);
PAINT GREEN (11738 3483);
FORCEPROP 2 LAST CDS_LIB mstr_standard
J 0
(11800 3475);
PAINT ORANGE (11800 3475);
DISPLAY INVISIBLE (11800 3475);
FORCEPROP 1 LAST BODY_TYPE PLUMBING
J 0
(11800 3525);
DISPLAY 0.872340 (11800 3525);
PAINT GREEN (11800 3525);
DISPLAY INVISIBLE (11800 3525);
FORCEPROP 1 LAST HDL_TAP TRUE
J 0
(12125 3350);
DISPLAY 0.872340 (12125 3350);
PAINT ORANGE (12125 3350);
DISPLAY INVISIBLE (12125 3350);
FORCEPROP 1 LAST PATH I7
J 0
(11798 3475);
DISPLAY 0.872340 (11798 3475);
PAINT GREEN (11798 3475);
DISPLAY INVISIBLE (11798 3475);
FORCEADD CAP_A..2
(11225 3475);
FORCEPROP 1 LAST LOCATION C1L3
J 1
(11225 3575);
DISPLAY 0.617021 (11225 3575);
PAINT AQUA (11225 3575);
FORCEPROP 1 LAST PART_NUMBER A36096-045
J 1
(11225 3525);
DISPLAY 0.617021 (11225 3525);
PAINT BLUE (11225 3525);
FORCEPROP 1 LAST VALUE 0.01UF
J 2
(11225 3375);
DISPLAY 0.617021 (11225 3375);
PAINT SKYBLUE (11225 3375);
FORCEPROP 1 LAST TOLERANCE 10%
J 2
(11225 3325);
DISPLAY 0.617021 (11225 3325);
PAINT SKYBLUE (11225 3325);
FORCEPROP 1 LAST PACK_TYPE 0402V
J 1
(11225 3275);
DISPLAY 0.617021 (11225 3275);
PAINT SKYBLUE (11225 3275);
FORCEPROP 1 LAST VOLTAGE 25V
J 0
(11225 3375);
DISPLAY 0.617021 (11225 3375);
PAINT SKYBLUE (11225 3375);
FORCEPROP 1 LAST MATERIAL X7R
J 0
(11225 3325);
DISPLAY 0.617021 (11225 3325);
PAINT SKYBLUE (11225 3325);
FORCEPROP 2 LAST CDS_LOCATION C1L3
J 1
(11225 3575);
DISPLAY 0.617021 (11225 3575);
PAINT AQUA (11225 3575);
DISPLAY INVISIBLE (11225 3575);
FORCEPROP 2 LAST BOM_COST ST_SATA
J 0
(11175 3625);
DISPLAY 1.361702 (11175 3625);
PAINT ORANGE (11175 3625);
DISPLAY INVISIBLE (11175 3625);
FORCEPROP 2 LAST CDS_LIB dev_discrete
J 0
(11225 3475);
PAINT ORANGE (11225 3475);
DISPLAY INVISIBLE (11225 3475);
FORCEPROP 2 LAST CDS_SEC 1
J 0
(11225 3725);
DISPLAY 1.021277 (11225 3725);
PAINT ORANGE (11225 3725);
DISPLAY INVISIBLE (11225 3725);
FORCEPROP 2 LAST $SEC 1
J 0
(11225 3725);
DISPLAY 0.680851 (11225 3725);
PAINT MONO (11225 3725);
DISPLAY INVISIBLE (11225 3725);
FORCEPROP 1 LAST PATH I8
J 0
(11225 3675);
DISPLAY 0.978723 (11225 3675);
PAINT WHITE (11225 3675);
DISPLAY INVISIBLE (11225 3675);
FORCEPROP 2 LAST ROOM ST_SATA
J 0
(11175 3625);
DISPLAY 1.361702 (11175 3625);
PAINT ORANGE (11175 3625);
DISPLAY INVISIBLE (11175 3625);
FORCEPROP 1 LASTPIN (11125 3475) $PN 1
J 0
(11115 3490);
DISPLAY 0.787234 (11115 3490);
PAINT ORANGE (11115 3490);
DISPLAY INVISIBLE (11115 3490);
FORCEPROP 1 LASTPIN (11325 3475) $PN 2
J 0
(11310 3490);
DISPLAY 0.787234 (11310 3490);
PAINT ORANGE (11310 3490);
DISPLAY INVISIBLE (11310 3490);
FORCEADD CAP_A..2
(10925 3725);
FORCEPROP 1 LAST LOCATION C1L2
J 1
(10925 3825);
DISPLAY 0.617021 (10925 3825);
PAINT AQUA (10925 3825);
FORCEPROP 1 LAST PART_NUMBER A36096-045
J 1
(10925 3775);
DISPLAY 0.617021 (10925 3775);
PAINT BLUE (10925 3775);
FORCEPROP 1 LAST VALUE 0.01UF
J 2
(10925 3625);
DISPLAY 0.617021 (10925 3625);
PAINT SKYBLUE (10925 3625);
FORCEPROP 1 LAST TOLERANCE 10%
J 2
(10925 3575);
DISPLAY 0.617021 (10925 3575);
PAINT SKYBLUE (10925 3575);
FORCEPROP 1 LAST PACK_TYPE 0402V
J 1
(10925 3525);
DISPLAY 0.617021 (10925 3525);
PAINT SKYBLUE (10925 3525);
FORCEPROP 1 LAST VOLTAGE 25V
J 0
(10925 3625);
DISPLAY 0.617021 (10925 3625);
PAINT SKYBLUE (10925 3625);
FORCEPROP 1 LAST MATERIAL X7R
J 0
(10925 3575);
DISPLAY 0.617021 (10925 3575);
PAINT SKYBLUE (10925 3575);
FORCEPROP 2 LAST CDS_LOCATION C1L2
J 1
(10925 3825);
DISPLAY 0.617021 (10925 3825);
PAINT AQUA (10925 3825);
DISPLAY INVISIBLE (10925 3825);
FORCEPROP 2 LAST BOM_COST ST_SATA
J 0
(10875 3875);
DISPLAY 1.361702 (10875 3875);
PAINT ORANGE (10875 3875);
DISPLAY INVISIBLE (10875 3875);
FORCEPROP 2 LAST CDS_LIB dev_discrete
J 0
(10925 3725);
PAINT ORANGE (10925 3725);
DISPLAY INVISIBLE (10925 3725);
FORCEPROP 2 LAST CDS_SEC 1
J 0
(10925 3975);
DISPLAY 1.021277 (10925 3975);
PAINT ORANGE (10925 3975);
DISPLAY INVISIBLE (10925 3975);
FORCEPROP 2 LAST $SEC 1
J 0
(10925 3975);
DISPLAY 0.680851 (10925 3975);
PAINT MONO (10925 3975);
DISPLAY INVISIBLE (10925 3975);
FORCEPROP 1 LAST PATH I9
J 0
(10925 3925);
DISPLAY 0.978723 (10925 3925);
PAINT WHITE (10925 3925);
DISPLAY INVISIBLE (10925 3925);
FORCEPROP 2 LAST ROOM ST_SATA
J 0
(10875 3875);
DISPLAY 1.361702 (10875 3875);
PAINT ORANGE (10875 3875);
DISPLAY INVISIBLE (10875 3875);
FORCEPROP 1 LASTPIN (10825 3725) $PN 1
J 0
(10815 3740);
DISPLAY 0.787234 (10815 3740);
PAINT ORANGE (10815 3740);
DISPLAY INVISIBLE (10815 3740);
FORCEPROP 1 LASTPIN (11025 3725) $PN 2
J 0
(11010 3740);
DISPLAY 0.787234 (11010 3740);
PAINT ORANGE (11010 3740);
DISPLAY INVISIBLE (11010 3740);
FORCEADD DESIGN_NOTE..1
(8525 3775);
FORCEPROP 0 LAST L1 MINI-SAS CONN SSATA 2-5
J 0
(8400 3650);
DISPLAY 0.829787 (8400 3650);
PAINT WHITE (8400 3650);
FORCEPROP 2 LAST CDS_LIB mstr_symbols
J 0
(8525 3775);
PAINT ORANGE (8525 3775);
DISPLAY INVISIBLE (8525 3775);
FORCEPROP 2 LAST BOM_COST ST_SATA
J 0
(8400 3600);
DISPLAY 1.361702 (8400 3600);
PAINT ORANGE (8400 3600);
DISPLAY INVISIBLE (8400 3600);
FORCEPROP 1 LAST COMMENT_BODY TRUE
J 0
(8550 3875);
DISPLAY 1.319149 (8550 3875);
PAINT ORANGE (8550 3875);
DISPLAY INVISIBLE (8550 3875);
FORCEPROP 2 LAST ROOM ST_SATA
J 0
(8400 3600);
DISPLAY 1.361702 (8400 3600);
PAINT ORANGE (8400 3600);
DISPLAY INVISIBLE (8400 3600);
FORCEADD CAD_NOTE..1
(6025 4125);
FORCEPROP 0 LAST L1 PLACE COMPONENTS CLOSE TO PCH
J 0
(5875 4000);
DISPLAY 0.829787 (5875 4000);
PAINT WHITE (5875 4000);
FORCEPROP 2 LAST BOM_COST ST_SATA
J 0
(5875 4050);
DISPLAY 1.361702 (5875 4050);
PAINT ORANGE (5875 4050);
DISPLAY INVISIBLE (5875 4050);
FORCEPROP 2 LAST CDS_LIB mstr_symbols
J 0
(6025 4125);
PAINT ORANGE (6025 4125);
DISPLAY INVISIBLE (6025 4125);
FORCEPROP 1 LAST COMMENT_BODY TRUE
J 0
(6050 4225);
DISPLAY 1.319149 (6050 4225);
PAINT ORANGE (6050 4225);
DISPLAY INVISIBLE (6050 4225);
FORCEPROP 2 LAST ROOM ST_SATA
J 0
(5875 4050);
DISPLAY 1.361702 (5875 4050);
PAINT ORANGE (5875 4050);
DISPLAY INVISIBLE (5875 4050);
FORCEADD CAD_NOTE..1
(6525 1400);
FORCEPROP 0 LAST L1 PLACE COMPONENTS CLOSE TO CONNECTOR
J 0
(6375 1250);
DISPLAY 0.829787 (6375 1250);
PAINT WHITE (6375 1250);
FORCEPROP 2 LAST BOM_COST ST_SATA
J 0
(6375 1300);
DISPLAY 1.361702 (6375 1300);
PAINT ORANGE (6375 1300);
DISPLAY INVISIBLE (6375 1300);
FORCEPROP 2 LAST CDS_LIB mstr_symbols
J 0
(6525 1400);
PAINT ORANGE (6525 1400);
DISPLAY INVISIBLE (6525 1400);
FORCEPROP 1 LAST COMMENT_BODY TRUE
J 0
(6550 1500);
DISPLAY 1.319149 (6550 1500);
PAINT ORANGE (6550 1500);
DISPLAY INVISIBLE (6550 1500);
FORCEPROP 2 LAST ROOM ST_SATA
J 0
(6375 1300);
DISPLAY 1.361702 (6375 1300);
PAINT ORANGE (6375 1300);
DISPLAY INVISIBLE (6375 1300);
FORCEADD CAD_NOTE..1
(10525 4125);
FORCEPROP 0 LAST L1 PLACE CAPS CLOSE TO PCH
J 0
(10375 4000);
DISPLAY 0.829787 (10375 4000);
PAINT WHITE (10375 4000);
FORCEPROP 2 LAST BOM_COST ST_SATA
J 0
(10375 4025);
DISPLAY 1.361702 (10375 4025);
PAINT ORANGE (10375 4025);
DISPLAY INVISIBLE (10375 4025);
FORCEPROP 2 LAST CDS_LIB mstr_symbols
J 0
(10525 4125);
PAINT ORANGE (10525 4125);
DISPLAY INVISIBLE (10525 4125);
FORCEPROP 1 LAST COMMENT_BODY TRUE
J 0
(10550 4225);
DISPLAY 1.319149 (10550 4225);
PAINT ORANGE (10550 4225);
DISPLAY INVISIBLE (10550 4225);
FORCEPROP 2 LAST ROOM ST_SATA
J 0
(10375 4025);
DISPLAY 1.361702 (10375 4025);
PAINT ORANGE (10375 4025);
DISPLAY INVISIBLE (10375 4025);
FORCEADD CAD_NOTE..1
(10200 1450);
FORCEPROP 0 LAST L1 PLACE CAPS CLOSE TO PCH
J 0
(10050 1325);
DISPLAY 0.829787 (10050 1325);
PAINT WHITE (10050 1325);
FORCEPROP 2 LAST BOM_COST ST_SATA
J 0
(10050 1375);
DISPLAY 1.361702 (10050 1375);
PAINT ORANGE (10050 1375);
DISPLAY INVISIBLE (10050 1375);
FORCEPROP 2 LAST CDS_LIB mstr_symbols
J 0
(10200 1450);
PAINT ORANGE (10200 1450);
DISPLAY INVISIBLE (10200 1450);
FORCEPROP 1 LAST COMMENT_BODY TRUE
J 0
(10225 1550);
DISPLAY 1.319149 (10225 1550);
PAINT ORANGE (10225 1550);
DISPLAY INVISIBLE (10225 1550);
FORCEPROP 2 LAST ROOM ST_SATA
J 0
(10050 1375);
DISPLAY 1.361702 (10050 1375);
PAINT ORANGE (10050 1375);
DISPLAY INVISIBLE (10050 1375);
FORCEADD INTEL_CORP_BPAGE..1
(12800 300);
FORCEPROP 1 LAST CDS_CON_LAST_MODIFIED Tue Dec 01 11:52:13 2015
J 0
(11375 625);
DISPLAY 1.382979 (11375 625);
PAINT GREEN (11375 625);
DISPLAY INVISIBLE (11375 625);
FORCEPROP 1 LAST CUSTOM_TXT_CDS <CURRENT_DESIGN_SHEET> OF <TOTAL_DESIGN_SHEETS>
J 0
(12300 325);
PAINT GREEN (12300 325);
FORCEPROP 2 LAST CUSTOM_TXT_CDS <XR_PAGE_TITLE>
J 0
(4910 5550);
DISPLAY 0.638298 (4910 5550);
PAINT PINK (4910 5550);
DISPLAY INVISIBLE (4910 5550);
FORCEPROP 2 LAST CUSTOM_TXT_CDS <CON_LAST_MODIFIED>
J 0
(10875 650);
DISPLAY 1.382979 (10875 650);
PAINT GREEN (10875 650);
FORCEPROP 1 LAST SCH_ADDRESS3 Santa Clara, CA 95052-8119
J 0
(8825 325);
DISPLAY 0.617021 (8825 325);
PAINT YELLOW (8825 325);
FORCEPROP 1 LAST SCH_ADDRESS2 P.O. BOX 58119
J 0
(8825 375);
DISPLAY 0.617021 (8825 375);
PAINT YELLOW (8825 375);
FORCEPROP 1 LAST SCH_ADDRESS1 2200 Mission College Blvd.
J 0
(8825 425);
DISPLAY 0.617021 (8825 425);
PAINT YELLOW (8825 425);
FORCEPROP 1 LAST SCH_TITLE MINI_SAS (2/2)
J 0
(4850 350);
DISPLAY 1.212766 (4850 350);
PAINT YELLOW (4850 350);
FORCEPROP 1 LAST SCH_REV 2.420
J 0
(12550 450);
DISPLAY 0.978723 (12550 450);
PAINT YELLOW (12550 450);
FORCEPROP 1 LAST SCH_DEPT BESD
J 1
(8350 400);
DISPLAY 1.212766 (8350 400);
PAINT YELLOW (8350 400);
FORCEPROP 1 LAST SCH_NUMBER H4694802
J 0
(11500 450);
DISPLAY 1.212766 (11500 450);
PAINT YELLOW (11500 450);
FORCEPROP 2 LAST PAGE_BORDER TRUE
J 0
(4910 5550);
DISPLAY 0.872340 (4910 5550);
PAINT PINK (4910 5550);
DISPLAY INVISIBLE (4910 5550);
FORCEPROP 2 LAST CDS_LIB mstr_symbols
J 0
(12800 300);
DISPLAY 1.382979 (12800 300);
PAINT ORANGE (12800 300);
DISPLAY INVISIBLE (12800 300);
FORCEPROP 1 LAST COMMENT_BODY TRUE
J 0
(12812 312);
DISPLAY 0.617021 (12812 312);
PAINT PEACH (12812 312);
DISPLAY INVISIBLE (12812 312);
FORCEPROP 2 LAST CDS_XR_PAGE_TITLE CR-174 : @BASEBOARD_FAB2_LIB.BASEBOARD_FAB2(SCH_1):PAGE174
J 0
(4910 5550);
DISPLAY 0.638298 (4910 5550);
PAINT PINK (4910 5550);
DISPLAY INVISIBLE (4910 5550);
WIRE 17 -1 (11850 3500)(11850 4425);
WIRE 17 -1 (11850 3500)(11850 3050);
WIRE 17 -1 (11850 4425)(11150 4425);
FORCEPROP 2 LAST SIG_NAME SATA6G_TX_DN<3:0>
J 0
(11215 4435);
DISPLAY 0.617021 (11215 4435);
PAINT ORANGE (11215 4435);
WIRE 17 -1 (11850 3050)(11850 2275);
WIRE 17 -1 (11850 2275)(11850 1850);
WIRE 17 -1 (12000 3750)(12000 3275);
WIRE 17 -1 (12000 3750)(12000 4575);
WIRE 17 -1 (12000 2500)(12000 3275);
WIRE 17 -1 (12000 2500)(12000 2050);
WIRE 17 -1 (11150 4575)(12000 4575);
FORCEPROP 2 LAST SIG_NAME SATA6G_TX_DP<3:0>
J 0
(11215 4585);
DISPLAY 0.617021 (11215 4585);
PAINT ORANGE (11215 4585);
WIRE 17 -1 (5400 3700)(5400 3250);
WIRE 17 -1 (5400 3700)(5400 4550);
WIRE 17 -1 (5400 3250)(5400 2500);
WIRE 17 -1 (5400 2500)(5400 2050);
WIRE 17 -1 (6650 4550)(5400 4550);
FORCEPROP 2 LAST SIG_NAME SATA6G_RX_DP<3:0>
J 0
(5840 4560);
DISPLAY 0.617021 (5840 4560);
PAINT ORANGE (5840 4560);
WIRE 17 -1 (5550 3050)(5550 2275);
WIRE 17 -1 (5550 3475)(5550 3050);
WIRE 17 -1 (5550 2275)(5550 1850);
WIRE 17 -1 (5550 3475)(5550 4400);
WIRE 17 -1 (5550 4400)(6650 4400);
FORCEPROP 2 LAST SIG_NAME SATA6G_RX_DN<3:0>
J 0
(5840 4410);
DISPLAY 0.617021 (5840 4410);
PAINT ORANGE (5840 4410);
WIRE 16 -1 (12250 2325)(12250 2175);
WIRE 16 -1 (9250 3425)(9425 3425);
WIRE 16 -1 (9425 3425)(9425 3175);
WIRE 16 -1 (9250 3175)(9425 3175);
WIRE 16 -1 (9425 2925)(9425 3175);
WIRE 16 -1 (9250 2925)(9425 2925);
WIRE 16 -1 (9425 2725)(9425 2925);
WIRE 16 -1 (9250 2725)(9425 2725);
WIRE 16 -1 (9425 2575)(9425 2725);
WIRE 16 -1 (9250 2575)(9425 2575);
WIRE 16 -1 (9425 2325)(9425 2575);
WIRE 16 -1 (9250 2325)(9425 2325);
WIRE 16 -1 (9425 2325)(9425 2075);
WIRE 16 -1 (9250 2075)(9425 2075);
WIRE 16 -1 (9425 2075)(9425 1900);
WIRE 16 -1 (7250 3700)(7250 3900);
WIRE 16 -1 (8050 3425)(7850 3425);
WIRE 16 -1 (7850 3425)(7850 3175);
WIRE 16 -1 (8050 3175)(7850 3175);
WIRE 16 -1 (7850 2925)(7850 3175);
WIRE 16 -1 (8050 2925)(7850 2925);
WIRE 16 -1 (7850 2775)(7850 2925);
WIRE 16 -1 (8050 2775)(7850 2775);
WIRE 16 -1 (7850 2575)(7850 2775);
WIRE 16 -1 (8050 2575)(7850 2575);
WIRE 16 -1 (7850 2325)(7850 2575);
WIRE 16 -1 (8050 2325)(7850 2325);
WIRE 16 -1 (7850 2075)(7850 2325);
WIRE 16 -1 (8050 2075)(7850 2075);
WIRE 16 -1 (7850 2075)(7850 1925);
WIRE 16 -1 (6425 3675)(5500 3675);
WIRE 16 -1 (6125 3450)(5650 3450);
WIRE 16 273 (5975 2775)(6725 2775);
WIRE 16 273 (5975 3875)(5975 2775);
WIRE 16 273 (6725 2775)(6725 3875);
WIRE 16 273 (6725 3875)(5975 3875);
WIRE 16 -1 (5650 3025)(6125 3025);
WIRE 16 -1 (5650 1825)(6200 1825);
WIRE 16 -1 (6500 2025)(5500 2025);
WIRE 16 -1 (6200 2250)(5650 2250);
WIRE 16 -1 (6500 2475)(5500 2475);
WIRE 16 -1 (6425 3225)(5500 3225);
WIRE 16 273 (6825 1550)(6825 2625);
WIRE 16 273 (6050 1550)(6825 1550);
WIRE 16 273 (6825 2625)(6050 2625);
WIRE 16 273 (6050 2625)(6050 1550);
WIRE 16 -1 (8050 2175)(7125 2175);
FORCEPROP 2 LAST SIG_NAME SATA6G_P11_RX_C_DN
J 0
(7275 2185);
DISPLAY 0.617021 (7275 2185);
PAINT ORANGE (7275 2185);
FORCEPROP 2 LASTPROP $XRERR UNIQUE?
J 0
(7035 2185);
DISPLAY 0.638298 (7035 2185);
PAINT MONO (7035 2185);
DISPLAY INVISIBLE (7035 2185);
WIRE 16 -1 (7125 2175)(7125 1825);
WIRE 16 -1 (7125 1825)(6400 1825);
WIRE 16 -1 (8050 2225)(7025 2225);
FORCEPROP 2 LAST SIG_NAME SATA6G_P11_RX_C_DP
J 0
(7275 2235);
DISPLAY 0.617021 (7275 2235);
PAINT ORANGE (7275 2235);
FORCEPROP 2 LASTPROP $XRERR UNIQUE?
J 0
(7035 2235);
DISPLAY 0.638298 (7035 2235);
PAINT MONO (7035 2235);
DISPLAY INVISIBLE (7035 2235);
WIRE 16 -1 (7025 2225)(7025 2025);
WIRE 16 -1 (7025 2025)(6700 2025);
WIRE 16 -1 (8050 2425)(6925 2425);
FORCEPROP 2 LAST SIG_NAME SATA6G_P10_RX_C_DN
J 0
(7275 2435);
DISPLAY 0.617021 (7275 2435);
PAINT ORANGE (7275 2435);
FORCEPROP 2 LASTPROP $XRERR UNIQUE?
J 0
(7035 2435);
DISPLAY 0.638298 (7035 2435);
PAINT MONO (7035 2435);
DISPLAY INVISIBLE (7035 2435);
WIRE 16 -1 (6925 2425)(6925 2250);
WIRE 16 -1 (6925 2250)(6400 2250);
WIRE 16 -1 (8050 3325)(7075 3325);
FORCEPROP 2 LAST SIG_NAME SATA6G_P8_RX_C_DP
J 0
(7275 3335);
DISPLAY 0.617021 (7275 3335);
PAINT ORANGE (7275 3335);
FORCEPROP 2 LASTPROP $XRERR UNIQUE?
J 0
(7035 3335);
DISPLAY 0.638298 (7035 3335);
PAINT MONO (7035 3335);
DISPLAY INVISIBLE (7035 3335);
WIRE 16 -1 (7075 3325)(7075 3675);
WIRE 16 -1 (7075 3675)(6625 3675);
WIRE 16 -1 (8050 3275)(6975 3275);
FORCEPROP 2 LAST SIG_NAME SATA6G_P8_RX_C_DN
J 0
(7275 3285);
DISPLAY 0.617021 (7275 3285);
PAINT ORANGE (7275 3285);
FORCEPROP 2 LASTPROP $XRERR UNIQUE?
J 0
(7035 3285);
DISPLAY 0.638298 (7035 3285);
PAINT MONO (7035 3285);
DISPLAY INVISIBLE (7035 3285);
WIRE 16 -1 (6975 3275)(6975 3450);
WIRE 16 -1 (6975 3450)(6325 3450);
WIRE 16 -1 (8050 3075)(6875 3075);
FORCEPROP 2 LAST SIG_NAME SATA6G_P9_RX_C_DP
J 0
(7275 3085);
DISPLAY 0.617021 (7275 3085);
PAINT ORANGE (7275 3085);
FORCEPROP 2 LASTPROP $XRERR UNIQUE?
J 0
(7035 3085);
DISPLAY 0.638298 (7035 3085);
PAINT MONO (7035 3085);
DISPLAY INVISIBLE (7035 3085);
WIRE 16 -1 (6875 3075)(6875 3225);
WIRE 16 -1 (6875 3225)(6625 3225);
WIRE 16 -1 (6325 3025)(8050 3025);
FORCEPROP 2 LAST SIG_NAME SATA6G_P9_RX_C_DN
J 0
(7275 3035);
DISPLAY 0.617021 (7275 3035);
PAINT ORANGE (7275 3035);
FORCEPROP 2 LASTPROP $XRERR UNIQUE?
J 0
(7035 3035);
DISPLAY 0.638298 (7035 3035);
PAINT MONO (7035 3035);
DISPLAY INVISIBLE (7035 3035);
WIRE 16 -1 (6700 2475)(8050 2475);
FORCEPROP 2 LAST SIG_NAME SATA6G_P10_RX_C_DP
J 0
(7275 2485);
DISPLAY 0.617021 (7275 2485);
PAINT ORANGE (7275 2485);
FORCEPROP 2 LASTPROP $XRERR UNIQUE?
J 0
(7035 2485);
DISPLAY 0.638298 (7035 2485);
PAINT MONO (7035 2485);
DISPLAY INVISIBLE (7035 2485);
WIRE 16 -1 (8050 2825)(6900 2825);
FORCEPROP 2 LAST SIG_NAME TP_FM_QAT_CBL_PRSNT2_N
J 0
(7275 2835);
DISPLAY 0.617021 (7275 2835);
PAINT ORANGE (7275 2835);
FORCEPROP 2 LASTPROP $XRERR UNIQUE?
J 0
(6660 2825);
DISPLAY 0.638298 (6660 2825);
PAINT MONO (6660 2825);
DISPLAY INVISIBLE (6660 2825);
WIRE 16 -1 (8050 2725)(7125 2725);
FORCEPROP 2 LAST SIG_NAME SGPIO_PCH_SSATA_DOUT0_R
J 0
(7275 2735);
DISPLAY 0.617021 (7275 2735);
PAINT ORANGE (7275 2735);
WIRE 16 -1 (7250 3500)(7250 2675);
WIRE 16 -1 (8050 2675)(7250 2675);
FORCEPROP 2 LAST SIG_NAME PU_DATAIN1_SATA_2
J 0
(7275 2685);
DISPLAY 0.617021 (7275 2685);
PAINT ORANGE (7275 2685);
FORCEPROP 2 LASTPROP $XRERR UNIQUE?
J 0
(7035 2685);
DISPLAY 0.638298 (7035 2685);
PAINT MONO (7035 2685);
DISPLAY INVISIBLE (7035 2685);
WIRE 16 -1 (10650 2025)(10150 2025);
WIRE 16 -1 (10150 2225)(10150 2025);
WIRE 16 -1 (10150 2225)(9250 2225);
FORCEPROP 2 LAST SIG_NAME SATA6G_P11_TX_C_DP
J 0
(9450 2235);
DISPLAY 0.617021 (9450 2235);
PAINT ORANGE (9450 2235);
FORCEPROP 2 LASTPROP $XRERR UNIQUE?
J 0
(9210 2235);
DISPLAY 0.638298 (9210 2235);
PAINT MONO (9210 2235);
DISPLAY INVISIBLE (9210 2235);
WIRE 16 -1 (10925 1825)(10050 1825);
WIRE 16 -1 (10050 2175)(10050 1825);
WIRE 16 -1 (10050 2175)(9250 2175);
FORCEPROP 2 LAST SIG_NAME SATA6G_P11_TX_C_DN
J 0
(9450 2185);
DISPLAY 0.617021 (9450 2185);
PAINT ORANGE (9450 2185);
FORCEPROP 2 LASTPROP $XRERR UNIQUE?
J 0
(9210 2185);
DISPLAY 0.638298 (9210 2185);
PAINT MONO (9210 2185);
DISPLAY INVISIBLE (9210 2185);
WIRE 16 -1 (10075 2825)(9250 2825);
FORCEPROP 2 LAST SIG_NAME SGPIO_PCH_SSATA_CLOCK_R
J 0
(9450 2835);
DISPLAY 0.617021 (9450 2835);
PAINT ORANGE (9450 2835);
WIRE 16 -1 (10075 2775)(9250 2775);
FORCEPROP 2 LAST SIG_NAME SGPIO_PCH_SSATA_LOAD_R
J 0
(9450 2785);
DISPLAY 0.617021 (9450 2785);
PAINT ORANGE (9450 2785);
WIRE 16 -1 (10825 3725)(10225 3725);
WIRE 16 -1 (10225 3325)(10225 3725);
WIRE 16 -1 (10225 3325)(9250 3325);
FORCEPROP 2 LAST SIG_NAME SATA6G_P8_TX_C_DP
J 0
(9450 3335);
DISPLAY 0.617021 (9450 3335);
PAINT ORANGE (9450 3335);
FORCEPROP 2 LASTPROP $XRERR UNIQUE?
J 0
(9210 3335);
DISPLAY 0.638298 (9210 3335);
PAINT MONO (9210 3335);
DISPLAY INVISIBLE (9210 3335);
WIRE 16 -1 (9250 2475)(10650 2475);
FORCEPROP 2 LAST SIG_NAME SATA6G_P10_TX_C_DP
J 0
(9450 2485);
DISPLAY 0.617021 (9450 2485);
PAINT ORANGE (9450 2485);
FORCEPROP 2 LASTPROP $XRERR UNIQUE?
J 0
(9210 2485);
DISPLAY 0.638298 (9210 2485);
PAINT MONO (9210 2485);
DISPLAY INVISIBLE (9210 2485);
WIRE 16 -1 (9250 3025)(11125 3025);
FORCEPROP 2 LAST SIG_NAME SATA6G_P9_TX_C_DN
J 0
(9450 3035);
DISPLAY 0.617021 (9450 3035);
PAINT ORANGE (9450 3035);
FORCEPROP 2 LASTPROP $XRERR UNIQUE?
J 0
(9210 3035);
DISPLAY 0.638298 (9210 3035);
PAINT MONO (9210 3035);
DISPLAY INVISIBLE (9210 3035);
WIRE 16 -1 (10850 2025)(11900 2025);
WIRE 16 -1 (11125 1825)(11750 1825);
WIRE 16 273 (11250 2650)(10475 2650);
WIRE 16 273 (11250 1600)(11250 2650);
WIRE 16 273 (10475 2650)(10475 1600);
WIRE 16 273 (10475 1600)(11250 1600);
WIRE 16 -1 (10925 2250)(10250 2250);
WIRE 16 -1 (10250 2425)(10250 2250);
WIRE 16 -1 (10250 2425)(9250 2425);
FORCEPROP 2 LAST SIG_NAME SATA6G_P10_TX_C_DN
J 0
(9450 2435);
DISPLAY 0.617021 (9450 2435);
PAINT ORANGE (9450 2435);
FORCEPROP 2 LASTPROP $XRERR UNIQUE?
J 0
(9210 2435);
DISPLAY 0.638298 (9210 2435);
PAINT MONO (9210 2435);
DISPLAY INVISIBLE (9210 2435);
WIRE 16 -1 (11125 3475)(10325 3475);
WIRE 16 -1 (10325 3275)(10325 3475);
WIRE 16 -1 (10325 3275)(9250 3275);
FORCEPROP 2 LAST SIG_NAME SATA6G_P8_TX_C_DN
J 0
(9450 3285);
DISPLAY 0.617021 (9450 3285);
PAINT ORANGE (9450 3285);
FORCEPROP 2 LASTPROP $XRERR UNIQUE?
J 0
(9210 3285);
DISPLAY 0.638298 (9210 3285);
PAINT MONO (9210 3285);
DISPLAY INVISIBLE (9210 3285);
WIRE 16 -1 (10825 3250)(10425 3250);
WIRE 16 -1 (10425 3075)(10425 3250);
WIRE 16 -1 (10425 3075)(9250 3075);
FORCEPROP 2 LAST SIG_NAME SATA6G_P9_TX_C_DP
J 0
(9450 3085);
DISPLAY 0.617021 (9450 3085);
PAINT ORANGE (9450 3085);
FORCEPROP 2 LASTPROP $XRERR UNIQUE?
J 0
(9210 3085);
DISPLAY 0.638298 (9210 3085);
PAINT MONO (9210 3085);
DISPLAY INVISIBLE (9210 3085);
WIRE 16 -1 (11025 3725)(11900 3725);
WIRE 16 -1 (10850 2475)(11900 2475);
WIRE 16 -1 (11125 2250)(11750 2250);
WIRE 16 -1 (11025 3250)(11900 3250);
WIRE 16 273 (11425 2775)(11425 3925);
WIRE 16 273 (10700 2775)(11425 2775);
WIRE 16 273 (11425 3925)(10700 3925);
WIRE 16 273 (10700 3925)(10700 2775);
WIRE 16 -1 (11325 3025)(11750 3025);
WIRE 16 -1 (12250 2675)(12250 2525);
WIRE 16 -1 (9250 2675)(12250 2675);
FORCEPROP 2 LAST SIG_NAME PD_SATA2_CONTROLLER_TYPE
J 0
(9450 2685);
DISPLAY 0.617021 (9450 2685);
PAINT ORANGE (9450 2685);
FORCEPROP 2 LASTPROP $XRERR UNIQUE?
J 0
(9210 2685);
DISPLAY 0.638298 (9210 2685);
PAINT MONO (9210 2685);
DISPLAY INVISIBLE (9210 2685);
WIRE 16 -1 (11325 3475)(11750 3475);
DOT 1 (9425 2725);
DOT 1 (7850 3175);
DOT 1 (7850 2075);
DOT 1 (7850 2325);
DOT 1 (7850 2925);
DOT 1 (9425 2075);
DOT 1 (9425 2325);
DOT 1 (9425 2575);
DOT 1 (9425 3175);
DOT 1 (7850 2575);
DOT 1 (7850 2775);
DOT 1 (9425 2925);
QUIT
